G04 ================== begin FILE IDENTIFICATION RECORD ==================*
G04 Layout Name:  13130-1b.brd*
G04 Film Name:    L4GND*
G04 File Format:  Gerber RS274X*
G04 File Origin:  Cadence Allegro 16.5-S037*
G04 Origin Date:  Thu Nov 13 17:26:57 2014*
G04 *
G04 Layer:  VIA CLASS/L4GND*
G04 Layer:  PIN/L4GND*
G04 Layer:  ETCH/L4GND*
G04 Layer:  DRAWING FORMAT/LAYER_PCB_STORY*
G04 Layer:  DRAWING FORMAT/LAYER_L4GND*
G04 *
G04 Offset:    (0.00 0.00)*
G04 Mirror:    No*
G04 Mode:      Negative*
G04 Rotation:  0*
G04 FullContactRelief:  No*
G04 UndefLineWidth:     6.00*
G04 ================== end FILE IDENTIFICATION RECORD ====================*
%FSLAX35Y35*MOIN*%
%IR0*IPPOS*OFA0.00000B0.00000*MIA0B0*SFA1.00000B1.00000*%
%ADD15C,.03*%
%ADD20C,.032*%
%ADD18C,.072*%
%ADD13C,.036*%
%ADD24C,.028*%
%ADD22C,.091*%
%ADD17C,.093*%
%ADD19C,.068*%
%AMMACRO23*
4,1,15,.00398,.00044,
.003999,.000208,
.004004,-.000025,
.003996,-.000258,
.00398,-.00044,
.00483,-.00129,
.004897,-.001007,
.004947,-.000721,
.004981,-.000432,
.004997,-.000141,
.004997,.000149,
.00498,.00044,
.004946,.000729,
.004895,.001015,
.00483,.00129,
.00398,.00044,
45.*
4,1,15,.00044,-.00398,
.000208,-.003999,
-.000025,-.004004,
-.000258,-.003996,
-.00044,-.00398,
-.00129,-.00483,
-.001007,-.004897,
-.000721,-.004947,
-.000432,-.004981,
-.000141,-.004997,
.000149,-.004997,
.00044,-.00498,
.000729,-.004946,
.001015,-.004895,
.00129,-.00483,
.00044,-.00398,
45.*
4,1,15,-.00398,-.00044,
-.003999,-.000208,
-.004004,.000025,
-.003996,.000258,
-.00398,.00044,
-.00483,.00129,
-.004897,.001007,
-.004947,.000721,
-.004981,.000432,
-.004997,.000141,
-.004997,-.000149,
-.00498,-.00044,
-.004946,-.000729,
-.004895,-.001015,
-.00483,-.00129,
-.00398,-.00044,
45.*
4,1,15,-.00044,.00398,
-.000208,.003999,
.000025,.004004,
.000258,.003996,
.00044,.00398,
.00129,.00483,
.001007,.004897,
.000721,.004947,
.000432,.004981,
.000141,.004997,
-.000149,.004997,
-.00044,.00498,
-.000729,.004946,
-.001015,.004895,
-.00129,.00483,
-.00044,.00398,
45.*
%
%ADD23MACRO23*%
%AMMACRO14*
4,1,15,.00398,.00044,
.003999,.000208,
.004004,-.000025,
.003996,-.000258,
.00398,-.00044,
.00483,-.00129,
.004897,-.001007,
.004947,-.000721,
.004981,-.000432,
.004997,-.000141,
.004997,.000149,
.00498,.00044,
.004946,.000729,
.004895,.001015,
.00483,.00129,
.00398,.00044,
90.*
4,1,15,.00044,-.00398,
.000208,-.003999,
-.000025,-.004004,
-.000258,-.003996,
-.00044,-.00398,
-.00129,-.00483,
-.001007,-.004897,
-.000721,-.004947,
-.000432,-.004981,
-.000141,-.004997,
.000149,-.004997,
.00044,-.00498,
.000729,-.004946,
.001015,-.004895,
.00129,-.00483,
.00044,-.00398,
90.*
4,1,15,-.00398,-.00044,
-.003999,-.000208,
-.004004,.000025,
-.003996,.000258,
-.00398,.00044,
-.00483,.00129,
-.004897,.001007,
-.004947,.000721,
-.004981,.000432,
-.004997,.000141,
-.004997,-.000149,
-.00498,-.00044,
-.004946,-.000729,
-.004895,-.001015,
-.00483,-.00129,
-.00398,-.00044,
90.*
4,1,15,-.00044,.00398,
-.000208,.003999,
.000025,.004004,
.000258,.003996,
.00044,.00398,
.00129,.00483,
.001007,.004897,
.000721,.004947,
.000432,.004981,
.000141,.004997,
-.000149,.004997,
-.00044,.00498,
-.000729,.004946,
-.001015,.004895,
-.00129,.00483,
-.00044,.00398,
90.*
%
%ADD14MACRO14*%
%AMMACRO12*
4,1,15,.00398,.00044,
.003999,.000208,
.004004,-.000025,
.003996,-.000258,
.00398,-.00044,
.00483,-.00129,
.004897,-.001007,
.004947,-.000721,
.004981,-.000432,
.004997,-.000141,
.004997,.000149,
.00498,.00044,
.004946,.000729,
.004895,.001015,
.00483,.00129,
.00398,.00044,
0.0*
4,1,15,.00044,-.00398,
.000208,-.003999,
-.000025,-.004004,
-.000258,-.003996,
-.00044,-.00398,
-.00129,-.00483,
-.001007,-.004897,
-.000721,-.004947,
-.000432,-.004981,
-.000141,-.004997,
.000149,-.004997,
.00044,-.00498,
.000729,-.004946,
.001015,-.004895,
.00129,-.00483,
.00044,-.00398,
0.0*
4,1,15,-.00398,-.00044,
-.003999,-.000208,
-.004004,.000025,
-.003996,.000258,
-.00398,.00044,
-.00483,.00129,
-.004897,.001007,
-.004947,.000721,
-.004981,.000432,
-.004997,.000141,
-.004997,-.000149,
-.00498,-.00044,
-.004946,-.000729,
-.004895,-.001015,
-.00483,-.00129,
-.00398,-.00044,
0.0*
4,1,15,-.00044,.00398,
-.000208,.003999,
.000025,.004004,
.000258,.003996,
.00044,.00398,
.00129,.00483,
.001007,.004897,
.000721,.004947,
.000432,.004981,
.000141,.004997,
-.000149,.004997,
-.00044,.00498,
-.000729,.004946,
-.001015,.004895,
-.00129,.00483,
-.00044,.00398,
0.0*
%
%ADD12MACRO12*%
%AMMACRO31*
4,1,14,.02782,.01368,
.029773,.008641,
.030821,.00334,
.030933,-.002063,
.030105,-.007403,
.028362,-.012518,
.02782,-.01368,
.03153,-.01738,
.034069,-.011641,
.035573,-.005548,
.035996,.000713,
.035325,.006953,
.033581,.012982,
.03153,.01738,
.02782,.01368,
270.*
4,1,14,.01368,-.02782,
.008641,-.029773,
.00334,-.030821,
-.002063,-.030933,
-.007403,-.030105,
-.012518,-.028362,
-.01368,-.02782,
-.01738,-.03153,
-.011641,-.034069,
-.005548,-.035573,
.000713,-.035996,
.006953,-.035325,
.012982,-.033581,
.01738,-.03153,
.01368,-.02782,
270.*
4,1,14,-.02782,-.01368,
-.029773,-.008641,
-.030821,-.00334,
-.030933,.002063,
-.030105,.007403,
-.028362,.012518,
-.02782,.01368,
-.03153,.01738,
-.034069,.011641,
-.035573,.005548,
-.035996,-.000713,
-.035325,-.006953,
-.033581,-.012982,
-.03153,-.01738,
-.02782,-.01368,
270.*
4,1,14,-.01368,.02782,
-.008641,.029773,
-.00334,.030821,
.002063,.030933,
.007403,.030105,
.012518,.028362,
.01368,.02782,
.01738,.03153,
.011641,.034069,
.005548,.035573,
-.000713,.035996,
-.006953,.035325,
-.012982,.033581,
-.01738,.03153,
-.01368,.02782,
270.*
%
%ADD31MACRO31*%
%ADD29O,.217X.154*%
%ADD11C,.114*%
%ADD16C,.154*%
%ADD21C,.147*%
%ADD10C,.168*%
%AMMACRO30*
4,1,15,.00398,.00044,
.003999,.000208,
.004004,-.000025,
.003996,-.000258,
.00398,-.00044,
.00483,-.00129,
.004897,-.001007,
.004947,-.000721,
.004981,-.000432,
.004997,-.000141,
.004997,.000149,
.00498,.00044,
.004946,.000729,
.004895,.001015,
.00483,.00129,
.00398,.00044,
225.*
4,1,15,.00044,-.00398,
.000208,-.003999,
-.000025,-.004004,
-.000258,-.003996,
-.00044,-.00398,
-.00129,-.00483,
-.001007,-.004897,
-.000721,-.004947,
-.000432,-.004981,
-.000141,-.004997,
.000149,-.004997,
.00044,-.00498,
.000729,-.004946,
.001015,-.004895,
.00129,-.00483,
.00044,-.00398,
225.*
4,1,15,-.00398,-.00044,
-.003999,-.000208,
-.004004,.000025,
-.003996,.000258,
-.00398,.00044,
-.00483,.00129,
-.004897,.001007,
-.004947,.000721,
-.004981,.000432,
-.004997,.000141,
-.004997,-.000149,
-.00498,-.00044,
-.004946,-.000729,
-.004895,-.001015,
-.00483,-.00129,
-.00398,-.00044,
225.*
4,1,15,-.00044,.00398,
-.000208,.003999,
.000025,.004004,
.000258,.003996,
.00044,.00398,
.00129,.00483,
.001007,.004897,
.000721,.004947,
.000432,.004981,
.000141,.004997,
-.000149,.004997,
-.00044,.00498,
-.000729,.004946,
-.001015,.004895,
-.00129,.00483,
-.00044,.00398,
225.*
%
%ADD30MACRO30*%
%AMMACRO28*
4,1,15,.00398,.00044,
.003999,.000208,
.004004,-.000025,
.003996,-.000258,
.00398,-.00044,
.00483,-.00129,
.004897,-.001007,
.004947,-.000721,
.004981,-.000432,
.004997,-.000141,
.004997,.000149,
.00498,.00044,
.004946,.000729,
.004895,.001015,
.00483,.00129,
.00398,.00044,
315.*
4,1,15,.00044,-.00398,
.000208,-.003999,
-.000025,-.004004,
-.000258,-.003996,
-.00044,-.00398,
-.00129,-.00483,
-.001007,-.004897,
-.000721,-.004947,
-.000432,-.004981,
-.000141,-.004997,
.000149,-.004997,
.00044,-.00498,
.000729,-.004946,
.001015,-.004895,
.00129,-.00483,
.00044,-.00398,
315.*
4,1,15,-.00398,-.00044,
-.003999,-.000208,
-.004004,.000025,
-.003996,.000258,
-.00398,.00044,
-.00483,.00129,
-.004897,.001007,
-.004947,.000721,
-.004981,.000432,
-.004997,.000141,
-.004997,-.000149,
-.00498,-.00044,
-.004946,-.000729,
-.004895,-.001015,
-.00483,-.00129,
-.00398,-.00044,
315.*
4,1,15,-.00044,.00398,
-.000208,.003999,
.000025,.004004,
.000258,.003996,
.00044,.00398,
.00129,.00483,
.001007,.004897,
.000721,.004947,
.000432,.004981,
.000141,.004997,
-.000149,.004997,
-.00044,.00498,
-.000729,.004946,
-.001015,.004895,
-.00129,.00483,
-.00044,.00398,
315.*
%
%ADD28MACRO28*%
%AMMACRO27*
4,1,15,.00398,.00044,
.003999,.000208,
.004004,-.000025,
.003996,-.000258,
.00398,-.00044,
.00483,-.00129,
.004897,-.001007,
.004947,-.000721,
.004981,-.000432,
.004997,-.000141,
.004997,.000149,
.00498,.00044,
.004946,.000729,
.004895,.001015,
.00483,.00129,
.00398,.00044,
180.*
4,1,15,.00044,-.00398,
.000208,-.003999,
-.000025,-.004004,
-.000258,-.003996,
-.00044,-.00398,
-.00129,-.00483,
-.001007,-.004897,
-.000721,-.004947,
-.000432,-.004981,
-.000141,-.004997,
.000149,-.004997,
.00044,-.00498,
.000729,-.004946,
.001015,-.004895,
.00129,-.00483,
.00044,-.00398,
180.*
4,1,15,-.00398,-.00044,
-.003999,-.000208,
-.004004,.000025,
-.003996,.000258,
-.00398,.00044,
-.00483,.00129,
-.004897,.001007,
-.004947,.000721,
-.004981,.000432,
-.004997,.000141,
-.004997,-.000149,
-.00498,-.00044,
-.004946,-.000729,
-.004895,-.001015,
-.00483,-.00129,
-.00398,-.00044,
180.*
4,1,15,-.00044,.00398,
-.000208,.003999,
.000025,.004004,
.000258,.003996,
.00044,.00398,
.00129,.00483,
.001007,.004897,
.000721,.004947,
.000432,.004981,
.000141,.004997,
-.000149,.004997,
-.00044,.00498,
-.000729,.004946,
-.001015,.004895,
-.00129,.00483,
-.00044,.00398,
180.*
%
%ADD27MACRO27*%
%AMMACRO26*
4,1,15,.00398,.00044,
.003999,.000208,
.004004,-.000025,
.003996,-.000258,
.00398,-.00044,
.00483,-.00129,
.004897,-.001007,
.004947,-.000721,
.004981,-.000432,
.004997,-.000141,
.004997,.000149,
.00498,.00044,
.004946,.000729,
.004895,.001015,
.00483,.00129,
.00398,.00044,
270.*
4,1,15,.00044,-.00398,
.000208,-.003999,
-.000025,-.004004,
-.000258,-.003996,
-.00044,-.00398,
-.00129,-.00483,
-.001007,-.004897,
-.000721,-.004947,
-.000432,-.004981,
-.000141,-.004997,
.000149,-.004997,
.00044,-.00498,
.000729,-.004946,
.001015,-.004895,
.00129,-.00483,
.00044,-.00398,
270.*
4,1,15,-.00398,-.00044,
-.003999,-.000208,
-.004004,.000025,
-.003996,.000258,
-.00398,.00044,
-.00483,.00129,
-.004897,.001007,
-.004947,.000721,
-.004981,.000432,
-.004997,.000141,
-.004997,-.000149,
-.00498,-.00044,
-.004946,-.000729,
-.004895,-.001015,
-.00483,-.00129,
-.00398,-.00044,
270.*
4,1,15,-.00044,.00398,
-.000208,.003999,
.000025,.004004,
.000258,.003996,
.00044,.00398,
.00129,.00483,
.001007,.004897,
.000721,.004947,
.000432,.004981,
.000141,.004997,
-.000149,.004997,
-.00044,.00498,
-.000729,.004946,
-.001015,.004895,
-.00129,.00483,
-.00044,.00398,
270.*
%
%ADD26MACRO26*%
%AMMACRO25*
4,1,15,.00398,.00044,
.003999,.000208,
.004004,-.000025,
.003996,-.000258,
.00398,-.00044,
.00483,-.00129,
.004897,-.001007,
.004947,-.000721,
.004981,-.000432,
.004997,-.000141,
.004997,.000149,
.00498,.00044,
.004946,.000729,
.004895,.001015,
.00483,.00129,
.00398,.00044,
135.*
4,1,15,.00044,-.00398,
.000208,-.003999,
-.000025,-.004004,
-.000258,-.003996,
-.00044,-.00398,
-.00129,-.00483,
-.001007,-.004897,
-.000721,-.004947,
-.000432,-.004981,
-.000141,-.004997,
.000149,-.004997,
.00044,-.00498,
.000729,-.004946,
.001015,-.004895,
.00129,-.00483,
.00044,-.00398,
135.*
4,1,15,-.00398,-.00044,
-.003999,-.000208,
-.004004,.000025,
-.003996,.000258,
-.00398,.00044,
-.00483,.00129,
-.004897,.001007,
-.004947,.000721,
-.004981,.000432,
-.004997,.000141,
-.004997,-.000149,
-.00498,-.00044,
-.004946,-.000729,
-.004895,-.001015,
-.00483,-.00129,
-.00398,-.00044,
135.*
4,1,15,-.00044,.00398,
-.000208,.003999,
.000025,.004004,
.000258,.003996,
.00044,.00398,
.00129,.00483,
.001007,.004897,
.000721,.004947,
.000432,.004981,
.000141,.004997,
-.000149,.004997,
-.00044,.00498,
-.000729,.004946,
-.001015,.004895,
-.00129,.00483,
-.00044,.00398,
135.*
%
%ADD25MACRO25*%
%ADD32C,.02*%
%ADD33C,.006*%
%ADD41C,.03004*%
%ADD39C,.06404*%
%ADD38C,.06804*%
%ADD40C,.08704*%
%ADD37C,.08904*%
%ADD34O,.21302X.15002*%
%ADD35C,.11004*%
%ADD36C,.15004*%
G75*
%LPD*%
G75*
G36*
G01X-6000Y-6000D02*
X832773D01*
Y296551D01*
X-6000D01*
Y-6000D01*
G37*
%LPC*%
G75*
G36*
G01X3937Y60878D02*
G02X3004Y61811I0J933D01*
G01Y286614D01*
G02X3937Y287547I933J0D01*
G01X193177D01*
G02X193514Y286932I0J-400D01*
G03X206880I6683J-4255D01*
G02X207217Y287547I337J215D01*
G01X291579D01*
G02X291917Y286933I0J-400D01*
G03X305327I6705J-4256D01*
G02X305665Y287547I338J214D01*
G01X822835D01*
G02X823768Y286614I0J-933D01*
G01Y3937D01*
G02X822835Y3004I-933J0D01*
G01X417323D01*
G02X416390Y3937I0J933D01*
G01Y42126D01*
G03X409449Y49067I-6941J0D01*
G01X393701D01*
G03X386760Y42126I0J-6941D01*
G01Y20648D01*
X348673D01*
Y39961D01*
G03X335185I-6744J0D01*
G01Y20648D01*
X60878D01*
Y53937D01*
G03X53937Y60878I-6941J0D01*
G01X3937D01*
G37*
%LPD*%
G75*
G36*
G01X9110Y260712D02*
G02X6090Y260713I-1510J1D01*
G01Y264483D01*
G02X9110I1510J0D01*
G01Y260712D01*
G37*
G36*
G01X15100Y254750D02*
G02X12080Y254751I-1510J1D01*
G01Y258521D01*
G02X15100I1510J0D01*
G01Y254750D01*
G37*
G36*
G01X39410Y253999D02*
G02X36390Y254000I-1510J1D01*
G01Y257500D01*
G02X39410I1510J0D01*
G01Y253999D01*
G37*
G36*
G01X9110Y248902D02*
G02X6090I-1510J0D01*
G01Y252673D01*
G02X9110Y252672I1510J-1D01*
G01Y248902D01*
G37*
G36*
G01X36397Y246861D02*
X36381Y247035D01*
X36481Y250542D01*
X36489Y250550D01*
X36495Y250624D01*
G02X39503Y250639I1505J-123D01*
G01X39519Y250465D01*
X39419Y246957D01*
X39394Y246785D01*
G02X36397Y246861I-1494J216D01*
G37*
G36*
G01X400528Y242794D02*
G02X398368Y244905I-1090J1045D01*
G01X400768Y247314D01*
G02X402908Y245182I1070J-1066D01*
G01X400529Y242795D01*
X400528Y242794D01*
G37*
G36*
G01X15100Y242939D02*
G02X12080Y242940I-1510J1D01*
G01Y246710D01*
G02X15100I1510J0D01*
G01Y242939D01*
G37*
G36*
G01X39410Y239999D02*
G02X36390Y240000I-1510J1D01*
G01Y243500D01*
G02X39410I1510J0D01*
G01Y239999D01*
G37*
G36*
G01X390616Y239712D02*
X390725Y239846D01*
X393170Y242218D01*
X393181D01*
X393237Y242267D01*
G02X395280Y240044I991J-1139D01*
G01X395137Y239905D01*
X395143Y239898D01*
X392844Y237667D01*
X392707Y237562D01*
G02X390616Y239712I-919J1198D01*
G37*
G36*
G01X9110Y237090D02*
G02X6090Y237091I-1510J1D01*
G01Y240861D01*
G02X9110I1510J0D01*
G01Y237090D01*
G37*
G36*
G01X36397Y232861D02*
X36381Y233035D01*
X36481Y236542D01*
X36489Y236550D01*
X36495Y236624D01*
G02X39503Y236639I1505J-123D01*
G01X39519Y236465D01*
X39419Y232957D01*
X39394Y232785D01*
G02X36397Y232861I-1494J216D01*
G37*
G36*
G01X14600Y231129D02*
G02X11580I-1510J0D01*
G01Y234900D01*
G02X14600Y234899I1510J-1D01*
G01Y231129D01*
G37*
G36*
G01X39410Y225999D02*
G02X36390Y226000I-1510J1D01*
G01Y229500D01*
G02X39410I1510J0D01*
G01Y225999D01*
G37*
G36*
G01Y218999D02*
G02X36390Y219000I-1510J1D01*
G01Y222500D01*
G02X39410I1510J0D01*
G01Y218999D01*
G37*
G36*
G01X329534Y219215D02*
G02X327485Y217426I-1025J-895D01*
G01X325999Y219130D01*
G02X328049Y220918I1025J894D01*
G01X329534Y219215D01*
G37*
G36*
G01X359255Y215107D02*
X359109Y215175D01*
X357235Y216357D01*
Y216365D01*
X357154Y216425D01*
G02X358692Y218666I812J1091D01*
G01X358861Y218559D01*
X358866Y218567D01*
X360570Y217492D01*
X360694Y217389D01*
G02X359255Y215107I-867J-1048D01*
G37*
G36*
G01X338701Y215752D02*
G02X335981Y215710I-1360J-21D01*
G01X335947Y217939D01*
G02X338667Y217982I1360J22D01*
G01X338701Y215752D01*
G37*
G36*
G01X344602Y213717D02*
G02X341882Y213663I-1360J-27D01*
G01X341838Y215882D01*
G02X344558Y215937I1360J27D01*
G01X344602Y213717D01*
G37*
G36*
G01X333018Y212687D02*
G02X330298Y212634I-1360J-26D01*
G01X330256Y214834D01*
G02X332976Y214886I1360J26D01*
G01X333018Y212687D01*
G37*
G36*
G01X354948Y210837D02*
G02X352240Y210578I-1354J-129D01*
G01X352031Y212769D01*
G02X354739Y213027I1354J129D01*
G01X354948Y210837D01*
G37*
G36*
G01X346240Y210141D02*
X346224Y210306D01*
X346295Y212525D01*
X346321Y212689D01*
G02X349017Y212612I1343J-213D01*
G01X349033Y212447D01*
X348962Y210234D01*
X348954Y210226D01*
X348947Y210154D01*
G02X346240Y210141I-1354J123D01*
G37*
G36*
G01X357162Y209968D02*
X357131Y210131D01*
X357014Y212358D01*
X357026Y212523D01*
G02X359740Y212498I1356J-97D01*
G01X359750Y212299D01*
X359761D01*
X359866Y210293D01*
X359859Y210286D01*
X359858Y210204D01*
G02X357162Y209968I-1360J16D01*
G37*
G36*
G01X337607Y209430D02*
X337566Y211648D01*
G02X340286Y211699I1360J26D01*
G01X340327Y209480D01*
G02X337607Y209430I-1360J-25D01*
G37*
G36*
G01X53370Y187640D02*
G02X50350I-1510J0D01*
G01Y191411D01*
G02X53370Y191410I1510J-1D01*
G01Y187640D01*
G37*
G36*
G01X200951Y187570D02*
G02X197931Y187525I-1510J-23D01*
G01X197882Y190925D01*
G02X200902Y190969I1510J22D01*
G01X200951Y187570D01*
G37*
G36*
G01X59379Y185890D02*
G02Y182870I0J-1510D01*
G01X55719D01*
G02X55720Y185890I1J1510D01*
G01X59379D01*
G37*
G36*
G01X241407Y180504D02*
G02X238393Y180697I-1507J97D01*
G01X238612Y184090D01*
G02X241626Y183896I1507J-97D01*
G01X241407Y180504D01*
G37*
G36*
G01X170910Y175350D02*
G02Y172330I0J-1510D01*
G01X167139D01*
G02X167140Y175350I1J1510D01*
G01X170910D01*
G37*
G36*
G01X177194Y171390D02*
G02X177125Y174410I-35J1510D01*
G01X180897Y174495D01*
G02X180965Y171475I34J-1510D01*
G01X177194Y171390D01*
G37*
G36*
G01X195638Y148605D02*
G02X193608Y150841I-1015J1118D01*
G01X196115Y153119D01*
X196116Y153120D01*
G02X198155Y150892I1024J-1110D01*
G01X195638Y148605D01*
G37*
G36*
G01X236385Y139289D02*
G02X233365Y139290I-1510J1D01*
G01Y143060D01*
G02X236385I1510J0D01*
G01Y139289D01*
G37*
G36*
G01X210551Y140538D02*
G02X210542Y137518I-5J-1510D01*
G01X206785Y137530D01*
G02X206795Y140550I5J1510D01*
G01X210551Y140538D01*
G37*
G36*
G01X205380Y135710D02*
G02Y132690I0J-1510D01*
G01X201898D01*
G02X201899Y135710I1J1510D01*
G01X205380D01*
G37*
G36*
G01X152180Y115499D02*
G02X149160Y115500I-1510J1D01*
G01Y118900D01*
G02X152180I1510J0D01*
G01Y115499D01*
G37*
G36*
G01X210769Y113771D02*
G02X207749I-1510J0D01*
G01Y117431D01*
G02X210769Y117430I1510J-1D01*
G01Y113771D01*
G37*
G36*
G01X273710Y108360D02*
G02X270690Y108345I-1510J-7D01*
G01X270675Y111824D01*
G02X273695Y111838I1510J7D01*
G01X273710Y108360D01*
G37*
G36*
G01X197845Y81870D02*
G02Y78850I0J-1510D01*
G01X194074D01*
G02X194075Y81870I1J1510D01*
G01X197845D01*
G37*
G36*
G01X82886Y62489D02*
G02X82885Y59469I-1J-1510D01*
G01X79115D01*
G02Y62489I0J1510D01*
G01X82886D01*
G37*
G36*
G01X290200Y59410D02*
G02Y56390I0J-1510D01*
G01X286799D01*
G02X286800Y59410I1J1510D01*
G01X290200D01*
G37*
G36*
G01X271000Y59010D02*
G02Y55990I0J-1510D01*
G01X267999D01*
G02X268000Y59010I1J1510D01*
G01X271000D01*
G37*
G36*
G01X319201Y58910D02*
G02X319200Y55890I-1J-1510D01*
G01X315800D01*
G02Y58910I0J1510D01*
G01X319201D01*
G37*
G36*
G01X308200D02*
G02Y55890I0J-1510D01*
G01X304799D01*
G02X304800Y58910I1J1510D01*
G01X308200D01*
G37*
G36*
G01X135001D02*
G02X135000Y55890I-1J-1510D01*
G01X131600D01*
G02Y58910I0J1510D01*
G01X135001D01*
G37*
G36*
G01X119201D02*
G02X119200Y55890I-1J-1510D01*
G01X115800D01*
G02Y58910I0J1510D01*
G01X119201D01*
G37*
G36*
G01X327400Y56410D02*
G02Y53390I0J-1510D01*
G01X323999D01*
G02X324000Y56410I1J1510D01*
G01X327400D01*
G37*
G36*
G01X208701D02*
G02X208700Y53390I-1J-1510D01*
G01X205300D01*
G02Y56410I0J1510D01*
G01X208701D01*
G37*
G36*
G01X166464Y55910D02*
G02X166463Y52890I-1J-1510D01*
G01X163063D01*
G02Y55910I0J1510D01*
G01X166464D01*
G37*
G36*
G01X150716D02*
G02X150715Y52890I-1J-1510D01*
G01X147315D01*
G02Y55910I0J1510D01*
G01X150716D01*
G37*
G36*
G01X103451D02*
G02X103450Y52890I-1J-1510D01*
G01X100050D01*
G02Y55910I0J1510D01*
G01X103451D01*
G37*
G36*
G01X88700D02*
G02Y52890I0J-1510D01*
G01X85299D01*
G02X85300Y55910I1J1510D01*
G01X88700D01*
G37*
G36*
G01X174061Y51110D02*
G02X174060Y48090I-1J-1510D01*
G01X170290D01*
G02Y51110I0J1510D01*
G01X174061D01*
G37*
G36*
G01X159060Y50120D02*
G02Y47100I0J-1510D01*
G01X155289D01*
G02X155290Y50120I1J1510D01*
G01X159060D01*
G37*
G36*
G01X236211Y44567D02*
G02Y41547I0J-1510D01*
G01X232590D01*
G02X232591Y44567I1J1510D01*
G01X236211D01*
G37*
G36*
G01X331931Y42505D02*
G02Y39485I0J-1510D01*
G01X328302D01*
G02X328303Y42505I1J1510D01*
G01X331931D01*
G37*
G36*
G01X316254Y42200D02*
G02Y39180I0J-1510D01*
G01X312483D01*
G02X312484Y42200I1J1510D01*
G01X316254D01*
G37*
G36*
G01X300506Y42000D02*
G02Y38980I0J-1510D01*
G01X296735D01*
G02X296736Y42000I1J1510D01*
G01X300506D01*
G37*
G36*
G01X284758D02*
G02Y38980I0J-1510D01*
G01X280987D01*
G02X280988Y42000I1J1510D01*
G01X284758D01*
G37*
G36*
G01X268911D02*
G02X268910Y38980I-1J-1510D01*
G01X265140D01*
G02Y42000I0J1510D01*
G01X268911D01*
G37*
G36*
G01X198073Y41905D02*
G02Y38885I0J-1510D01*
G01X194444D01*
G02X194445Y41905I1J1510D01*
G01X198073D01*
G37*
G36*
G01X245386Y41867D02*
G02X245385Y38847I-1J-1510D01*
G01X241765D01*
G02Y41867I0J1510D01*
G01X245386D01*
G37*
G36*
G01X190267D02*
G02Y38847I0J-1510D01*
G01X186646D01*
G02X186647Y41867I1J1510D01*
G01X190267D01*
G37*
G36*
G01X174519D02*
G02Y38847I0J-1510D01*
G01X170898D01*
G02X170899Y41867I1J1510D01*
G01X174519D01*
G37*
G36*
G01X158771D02*
G02Y38847I0J-1510D01*
G01X155150D01*
G02X155151Y41867I1J1510D01*
G01X158771D01*
G37*
G36*
G01X143024D02*
G02X143023Y38847I-1J-1510D01*
G01X139403D01*
G02Y41867I0J1510D01*
G01X143024D01*
G37*
G36*
G01X127276D02*
G02X127275Y38847I-1J-1510D01*
G01X123655D01*
G02Y41867I0J1510D01*
G01X127276D01*
G37*
G36*
G01X111528D02*
G02X111527Y38847I-1J-1510D01*
G01X107907D01*
G02Y41867I0J1510D01*
G01X111528D01*
G37*
G36*
G01X95779D02*
G02Y38847I0J-1510D01*
G01X92158D01*
G02X92159Y41867I1J1510D01*
G01X95779D01*
G37*
G36*
G01X80031D02*
G02Y38847I0J-1510D01*
G01X76410D01*
G02X76411Y41867I1J1510D01*
G01X80031D01*
G37*
G36*
G01X319026Y236350D02*
X316069D01*
G02Y239050I-69J1350D01*
G01X319031D01*
G02Y236350I69J-1350D01*
G01X319026D01*
G37*
G36*
G01X329939Y236762D02*
X329942Y236759D01*
X332041Y234668D01*
X332045Y234664D01*
G02X330148Y232742I-903J-1006D01*
G01X330145Y232745D01*
X328036Y234845D01*
X328033Y234848D01*
G02X329939Y236762I911J999D01*
G37*
G36*
G01X318550Y215226D02*
Y213169D01*
G02X315850I-1350J-69D01*
G01Y215231D01*
G02X318550I1350J69D01*
G01Y215226D01*
G37*
G36*
G01X322950Y210926D02*
Y208769D01*
G02X320250I-1350J-69D01*
G01Y210931D01*
G02X322950I1350J69D01*
G01Y210926D01*
G37*
G36*
G01X36300Y212122D02*
Y208373D01*
G02X33300I-1500J-73D01*
G01Y212127D01*
G02X36300I1500J73D01*
G01Y212122D01*
G37*
G36*
G01X33500Y203122D02*
Y199373D01*
G02X30500I-1500J-73D01*
G01Y203127D01*
G02X33500I1500J73D01*
G01Y203122D01*
G37*
G36*
G01X357750Y199311D02*
Y204811D01*
X361750Y208811D01*
Y223311D01*
X363750Y225311D01*
Y242311D01*
X368189Y246750D01*
X374811D01*
X380250Y241311D01*
Y224311D01*
X382250Y222311D01*
Y213189D01*
X381250Y212189D01*
Y196189D01*
X378750Y193689D01*
Y177811D01*
X380311Y176250D01*
X382189D01*
X382689Y176750D01*
X395504D01*
G02X395642I69J-1350D01*
G01X404311D01*
X406250Y174811D01*
Y164689D01*
X405250Y163689D01*
Y162311D01*
X405811Y161750D01*
X415311D01*
X417250Y159811D01*
Y157189D01*
X415311Y155250D01*
X412811D01*
X412750Y155189D01*
Y151689D01*
X411927Y150866D01*
G02X411545Y150481I-1527J1134D01*
G01X411534Y150473D01*
X411311Y150250D01*
X411146D01*
X411110Y150236D01*
G02X409690I-710J1764D01*
G01X409654Y150250D01*
X408811D01*
X404882Y146321D01*
X404867Y146280D01*
G02X403731Y145144I-1787J651D01*
G01X403690Y145129D01*
X402311Y143750D01*
X373689D01*
X369250Y148189D01*
Y153189D01*
X365189Y157250D01*
X356689D01*
X352750Y161189D01*
Y177811D01*
X354750Y179811D01*
Y187811D01*
X357750Y190811D01*
Y195689D01*
X357250Y196189D01*
Y198811D01*
X357750Y199311D01*
G37*
G36*
G01X307505Y124052D02*
X307509D01*
X309573Y124142D01*
X309578D01*
G02X309696Y121444I122J-1346D01*
G01X309691D01*
X307626Y121354D01*
X307621Y121353D01*
G02X307505Y124052I-121J1347D01*
G37*
G36*
G01X309107Y116351D02*
X307051Y116374D01*
X307046D01*
G02X307077Y119074I-52J1351D01*
G01X307081D01*
X309137Y119051D01*
X309142D01*
G02X309111Y116351I52J-1351D01*
G01X309107D01*
G37*
G36*
G01X253422Y56400D02*
X250573D01*
G02Y59400I-73J1500D01*
G01X253427D01*
G02Y56400I73J-1500D01*
G01X253422D01*
G37*
G36*
G01X261922Y56300D02*
X259073D01*
G02Y59300I-73J1500D01*
G01X261927D01*
G02Y56300I73J-1500D01*
G01X261922D01*
G37*
G36*
G01X197622Y52900D02*
X194773D01*
G02Y55900I-73J1500D01*
G01X197627D01*
G02Y52900I73J-1500D01*
G01X197622D01*
G37*
G36*
G01X181722D02*
X179073D01*
G02Y55900I-73J1500D01*
G01X181727D01*
G02Y52900I73J-1500D01*
G01X181722D01*
G37*
G36*
G01X189622Y52800D02*
X186938D01*
G02Y55800I-73J1500D01*
G01X189627D01*
G02Y52800I73J-1500D01*
G01X189622D01*
G37*
G54D41*
X37600Y198800D03*
Y203700D03*
X40400Y207800D03*
Y212700D03*
G54D39*
X144000Y67875D03*
Y147125D03*
G54D38*
X42717Y270472D03*
X235630Y75590D03*
X492520Y262598D03*
X761417Y22798D03*
G54D40*
X235630Y174016D03*
X498425Y22798D03*
X755512Y262598D03*
G54D37*
X42717Y191732D03*
G54D34*
X350197Y231103D03*
G54D35*
X11500Y68500D03*
X12000Y279000D03*
X816000Y280000D03*
G54D36*
X45669Y77185D03*
Y172460D03*
%LPC*%
G75*
G36*
G01X396926Y175250D02*
X403689D01*
X404750Y174189D01*
Y165311D01*
X403750Y164311D01*
Y161689D01*
X405189Y160250D01*
X414689D01*
X415750Y159189D01*
Y157811D01*
X414689Y156750D01*
X412189D01*
X411250Y155811D01*
Y152311D01*
X410689Y151750D01*
X408189D01*
X401689Y145250D01*
X374311D01*
X370750Y148811D01*
Y153811D01*
X365811Y158750D01*
X357311D01*
X354250Y161811D01*
Y177189D01*
X356250Y179189D01*
Y187189D01*
X359250Y190189D01*
Y196311D01*
X358750Y196811D01*
Y198189D01*
X359250Y198689D01*
Y204189D01*
X363250Y208189D01*
Y222689D01*
X365250Y224689D01*
Y241689D01*
X368811Y245250D01*
X374189D01*
X378750Y240689D01*
Y223689D01*
X380750Y221689D01*
Y213811D01*
X379750Y212811D01*
Y196811D01*
X377250Y194311D01*
Y177189D01*
X379689Y174750D01*
X382811D01*
X383311Y175250D01*
X394220D01*
X394256Y175095D01*
G03X396890I1317J305D01*
G01X396926Y175250D01*
G37*
%LPD*%
G75*
G54D15*
X17500Y190200D03*
X16844Y203100D03*
X13090Y231129D03*
Y234899D03*
X7600Y240861D03*
Y237091D03*
X13590Y242940D03*
Y254751D03*
X7600Y252672D03*
Y248902D03*
Y260713D03*
X13590Y258521D03*
Y246710D03*
X16900Y269000D03*
X7600Y264483D03*
X28400Y81400D03*
X30000Y136000D03*
X29700Y141200D03*
X26500Y181800D03*
X33500Y178100D03*
X33150Y181500D03*
X29400Y180000D03*
X23100Y181800D03*
X33500Y196100D03*
X32000Y203200D03*
Y199300D03*
X41200Y90300D03*
X42000Y96000D03*
X41500Y100800D03*
X40500Y124300D03*
X37600Y198800D03*
X37900Y195300D03*
X40400Y212700D03*
X34800Y208300D03*
X40400Y207800D03*
X34800Y212200D03*
X37600Y203700D03*
X44861Y227261D03*
X37900Y219000D03*
Y222500D03*
Y229500D03*
Y226000D03*
Y240000D03*
Y243500D03*
Y233000D03*
X38000Y236500D03*
X44400Y250400D03*
X37900Y257500D03*
Y254000D03*
Y247000D03*
X38000Y250500D03*
X46800Y274500D03*
X62900Y79900D03*
X60800Y87500D03*
X53500Y120400D03*
X57600Y136900D03*
X56100Y130700D03*
X52643Y130800D03*
X58000Y141750D03*
X58800Y177000D03*
X51860Y187640D03*
Y191410D03*
X59379Y184380D03*
X55720D03*
X57400Y210700D03*
X57009Y230009D03*
X57600Y226600D03*
X57500Y223200D03*
X57287Y219806D03*
X56724Y243300D03*
X56800Y249613D03*
X58102Y246471D03*
X57800Y253900D03*
X50000Y270000D03*
X57800Y264100D03*
X64700Y272500D03*
X57800Y267500D03*
X80031Y40357D03*
X76411D03*
X79700Y67500D03*
X79115Y60979D03*
X69235Y99735D03*
X68200Y94900D03*
Y91500D03*
X66500Y128000D03*
X65500Y123800D03*
X74800Y191000D03*
X72600Y244800D03*
X75600Y246700D03*
X79000Y246900D03*
X69400Y246000D03*
X75300Y259900D03*
X78200Y275600D03*
X71800Y268800D03*
X66800Y275200D03*
X74000Y271400D03*
X92159Y40357D03*
X88700Y54400D03*
X85300D03*
X90600Y63200D03*
X94000Y63300D03*
X82885Y60979D03*
X90000Y91000D03*
X91500Y84000D03*
X94500Y76200D03*
X89800Y87300D03*
X86100Y97700D03*
X90500Y101000D03*
X86500Y113500D03*
X80500D03*
X85500Y135400D03*
X83500Y191000D03*
X86900D03*
X84700Y197100D03*
X92900Y204008D03*
X89500Y204000D03*
X85898Y200598D03*
X95200Y216200D03*
X90812Y215000D03*
X80563Y214700D03*
X88900Y246700D03*
X82400Y246600D03*
X82100Y259600D03*
X80500Y269500D03*
X83900D03*
X95779Y40357D03*
X107907D03*
X109700Y60000D03*
X103450Y54400D03*
X100050D03*
X109600Y63700D03*
X96200Y60700D03*
X97900Y76200D03*
X106100Y158700D03*
X97100Y189200D03*
X110000Y201900D03*
X107740Y204460D03*
X102000Y203200D03*
X100600Y221100D03*
X110166Y239500D03*
X109500Y258300D03*
X97600Y246500D03*
X104900Y248800D03*
X120000Y40700D03*
X123655Y40357D03*
X111527D03*
X120200Y45610D03*
X119200Y57400D03*
X115800D03*
X111200Y67200D03*
X121170Y80900D03*
X121295Y77502D03*
X126000Y86200D03*
X125787Y78813D03*
X120700Y135500D03*
X118500Y125500D03*
X112550Y142800D03*
X119600Y143300D03*
X111900Y209000D03*
X112800Y225400D03*
X112700Y221200D03*
Y231400D03*
X136600Y44800D03*
X139403Y40357D03*
X127275D03*
X138000Y49800D03*
X138574Y57924D03*
X131600Y57400D03*
X135000D03*
X136469Y89902D03*
X130315Y90533D03*
X134200Y86100D03*
X137138Y76512D03*
X129300Y84900D03*
X136600Y93300D03*
X133558Y91779D03*
X136500Y104923D03*
X130000Y121000D03*
X136540Y108620D03*
X133975Y129141D03*
X130563Y125200D03*
X127500Y129180D03*
X126950Y125200D03*
X133786Y134700D03*
X130300Y135000D03*
X135412Y141400D03*
X138600Y146300D03*
X131500Y149000D03*
X136156Y138025D03*
X131762Y141796D03*
X127200Y158700D03*
X137300Y158900D03*
X140800D03*
X140000Y195500D03*
X137100Y188900D03*
X128000Y203300D03*
X143023Y40357D03*
X155151D03*
X144995Y57995D03*
X155290Y48610D03*
X143688Y48350D03*
X147400Y60400D03*
X147315Y54400D03*
X150715D03*
X153000Y67800D03*
X150894Y76497D03*
X154294Y76506D03*
X150670Y102720D03*
X154550Y106200D03*
X151080Y99344D03*
X154550Y102800D03*
X150670Y115500D03*
Y118900D03*
X157229Y119218D03*
X153693Y124807D03*
X147808Y145208D03*
X142900Y138595D03*
X146400D03*
X150804Y158896D03*
X144500Y158900D03*
X146980Y200580D03*
X153000Y201900D03*
X153500Y210000D03*
X146396Y207675D03*
X142997Y207891D03*
X150000Y210100D03*
X146500Y236500D03*
X146000Y231000D03*
X155300Y254000D03*
X144200Y270700D03*
X158771Y40357D03*
X170899D03*
X159060Y48610D03*
X170290Y49600D03*
X166463Y54400D03*
X163063D03*
X164000Y65000D03*
X172199Y91591D03*
X172300Y107189D03*
X158305Y112180D03*
X157500Y149025D03*
X158500Y161820D03*
X161900Y161700D03*
X167581Y164084D03*
X170910Y173840D03*
X167140D03*
X165900Y181500D03*
X163700Y178900D03*
X165700Y254000D03*
X174519Y40357D03*
X186647D03*
X174060Y49600D03*
X186865Y54300D03*
X181800Y54400D03*
X179000D03*
X179800Y65700D03*
X176900Y67500D03*
X180700Y78500D03*
X174900Y77700D03*
X183726Y106353D03*
X187500Y106500D03*
X173000Y97000D03*
X183344Y94056D03*
X179400Y94200D03*
X181732Y97500D03*
X178000Y97300D03*
X175787Y127000D03*
X176700Y144875D03*
X177200Y148700D03*
X181000Y167500D03*
X180931Y172985D03*
X177159Y172900D03*
X186300Y172400D03*
X174739Y207381D03*
X187000Y209500D03*
X198073Y40395D03*
X194445D03*
X190267Y40357D03*
X189700Y54300D03*
X197700Y54400D03*
X194700D03*
X190100Y68700D03*
X193500D03*
X194075Y80360D03*
X197845D03*
X202200Y89500D03*
X191500Y94100D03*
X188900Y91800D03*
X193005Y97155D03*
X195989Y95300D03*
X189106Y97235D03*
X201650Y111200D03*
X201899Y134200D03*
X194900Y124200D03*
X197140Y152010D03*
X194623Y149723D03*
X191200Y181068D03*
X199441Y187547D03*
X199392Y190947D03*
X202761Y186811D03*
X195630Y192770D03*
X198198Y206374D03*
X194800Y206100D03*
X201596Y206504D03*
X195000Y234000D03*
X205300Y54900D03*
X208700D03*
X214942Y67242D03*
X211600Y82100D03*
X212300Y85500D03*
X207200Y106000D03*
X209259Y113771D03*
Y117430D03*
X206605Y121741D03*
X209900Y120900D03*
X205380Y134200D03*
X210547Y139028D03*
X206790Y139040D03*
X215100Y194200D03*
X207861Y188540D03*
X215100Y199400D03*
X205000Y206500D03*
X215384Y202984D03*
X216000Y219500D03*
X208800D03*
X212500D03*
X206000Y234000D03*
X229300Y42950D03*
X232591Y43057D03*
X219900Y39100D03*
X223475Y53300D03*
X219899Y56800D03*
X233981Y59125D03*
X221400Y64500D03*
X230400Y63000D03*
X223800Y61700D03*
X230000Y66400D03*
X226500Y94450D03*
X227850Y97575D03*
X230875Y106300D03*
X227894Y104600D03*
X232600Y95300D03*
X227800Y101200D03*
X233452Y108588D03*
X228000Y108304D03*
Y139700D03*
X232921Y167505D03*
X227870Y170252D03*
X224200Y180200D03*
X232560Y204250D03*
X227000Y275500D03*
X236211Y43057D03*
X245385Y40357D03*
X241765D03*
X244400Y50600D03*
X235400Y63400D03*
X240297D03*
X243200Y73700D03*
X240300Y67200D03*
X246600Y73700D03*
X244759Y85200D03*
X236700Y88500D03*
X241200Y94900D03*
X244800Y100700D03*
X235075Y105600D03*
X234875Y139290D03*
Y143060D03*
X244715Y159785D03*
X239900Y180600D03*
X247596Y174667D03*
X240119Y183993D03*
X240100Y191000D03*
X246689Y196687D03*
X254600Y41100D03*
X265140Y40490D03*
X259000Y57800D03*
X250500Y57900D03*
X262000Y57800D03*
X253500Y57900D03*
X264500Y73100D03*
X253700Y75875D03*
X250300Y73800D03*
X264125Y79350D03*
X259820Y103454D03*
X262131Y100959D03*
X258634Y95850D03*
X263775Y140327D03*
X257977Y163423D03*
X264600Y173100D03*
X257687Y169870D03*
X253500Y174360D03*
X261300Y188300D03*
X253300Y189834D03*
X262700Y191500D03*
X261200Y209700D03*
X263600Y239850D03*
Y252700D03*
X257500Y266645D03*
X260500Y264630D03*
X269800Y44800D03*
X275300Y44900D03*
X278700Y44800D03*
X268910Y40490D03*
X278868Y56000D03*
X271000Y57500D03*
X268000D03*
X275200Y78700D03*
X275900Y88200D03*
X280100Y89100D03*
X272200Y108352D03*
X272185Y111831D03*
X278075Y116475D03*
X272300Y129442D03*
X268900Y129386D03*
X280400Y129225D03*
X272300Y149900D03*
X267187Y149800D03*
X278000Y141900D03*
X273900Y156198D03*
X270500Y163200D03*
X274100Y163300D03*
X267456Y160156D03*
X267100Y156200D03*
X272380Y159240D03*
X270500Y156250D03*
X268283Y173035D03*
X278300Y173300D03*
X276910Y189400D03*
X273060Y189374D03*
X266140Y191850D03*
X270341Y211835D03*
X278450Y216800D03*
X265259Y216659D03*
X270774Y222226D03*
X275400Y237900D03*
X267275Y253400D03*
X265500Y249300D03*
X269800Y250700D03*
X278700Y254240D03*
X275300Y254100D03*
X267000Y271300D03*
X284758Y40490D03*
X280988D03*
X286800Y57900D03*
X290200D03*
X288400Y94200D03*
X288100Y99500D03*
X281005Y99105D03*
X281475Y116475D03*
X286500Y119900D03*
X286600Y136000D03*
X287071Y173154D03*
X282950Y181350D03*
X282460Y189400D03*
X286300Y191885D03*
X293300Y212400D03*
X291201Y225025D03*
X287802Y225200D03*
X287600Y238100D03*
X287400Y254100D03*
X295500Y253500D03*
X281599Y261799D03*
X287250Y269250D03*
X296736Y40490D03*
X300506D03*
X300900Y46900D03*
X308200Y57400D03*
X304800D03*
X297150Y91100D03*
X309400Y82100D03*
X299800Y85950D03*
Y82300D03*
X304400Y88400D03*
X301300Y97000D03*
X301600Y93300D03*
X303400Y98500D03*
X303376Y95200D03*
X299300Y98500D03*
X296564Y136311D03*
Y127500D03*
X296531Y133061D03*
X301109Y146156D03*
X300700Y142850D03*
X297000Y160200D03*
X307231Y164059D03*
X310579Y182800D03*
X306612Y171882D03*
X304400Y182000D03*
X302591Y173906D03*
X309112Y171960D03*
X309200Y180500D03*
X305091Y173888D03*
X301745Y181788D03*
X307200Y182000D03*
X296600Y189100D03*
X305300Y203125D03*
X307300Y224900D03*
X304400D03*
X309900D03*
X298900Y253300D03*
X309400Y253600D03*
X306000D03*
X302600D03*
X304300Y262900D03*
X309000Y266700D03*
X311300Y277800D03*
X321900Y44000D03*
X312484Y40690D03*
X316254D03*
X314800Y48625D03*
X311950Y50800D03*
X320400Y48600D03*
X324000Y54900D03*
X324176Y48600D03*
X315800Y57400D03*
X319200D03*
X312400Y79700D03*
X312150Y100682D03*
X326000Y254100D03*
X315500D03*
X322500Y254200D03*
X319000D03*
X311400Y269200D03*
X326100Y267000D03*
X318600Y264300D03*
X313824Y280255D03*
X316945Y281606D03*
X316400Y276800D03*
X319400Y278800D03*
X322700Y277700D03*
X321600Y282500D03*
X325100Y281500D03*
X331931Y40995D03*
X328303D03*
X331300Y48475D03*
X327577D03*
X327400Y54900D03*
X333600Y63800D03*
X356432Y43657D03*
X356971Y37700D03*
X349900Y263800D03*
X342600Y277900D03*
X364600Y44298D03*
X367497Y41042D03*
X363604D03*
X371457Y37642D03*
X367520D03*
X366484Y47129D03*
X362626Y47068D03*
X366700Y68700D03*
X373000Y242300D03*
Y236000D03*
Y238900D03*
X385300Y47000D03*
X388000Y72963D03*
X382700Y275300D03*
X386100D03*
X379300D03*
X394229Y241128D03*
X391788Y238760D03*
X399438Y243839D03*
X401838Y246248D03*
X390500Y268800D03*
X393000Y275000D03*
X400900Y273000D03*
X391000Y265000D03*
X417000Y258000D03*
X416128Y272896D03*
X425400Y9103D03*
X422000D03*
X428800D03*
X432200D03*
X430000Y21500D03*
Y27358D03*
X424543Y22208D03*
Y27900D03*
X426405Y25054D03*
X427000Y17000D03*
X423500Y16885D03*
X423000Y43900D03*
X430000Y30758D03*
X424536Y34800D03*
X430000Y34158D03*
X424599Y31300D03*
X422986Y40350D03*
X430000Y244450D03*
X426600D03*
X420000Y244000D03*
X420500Y257800D03*
X433129Y245783D03*
X423600Y246700D03*
X423000Y274000D03*
X433300Y274100D03*
X426600D03*
X429900Y274940D03*
X442100Y7006D03*
X437061Y10393D03*
X434900Y6925D03*
X446800Y9900D03*
X438300Y6925D03*
X449600Y5900D03*
X446200D03*
X446100Y18700D03*
X441390Y28680D03*
X436240Y26300D03*
X449734Y18681D03*
X441281Y17025D03*
X436100Y30900D03*
X436106Y34506D03*
X435700Y243250D03*
X440600Y274300D03*
X449400Y273700D03*
X436600Y275000D03*
X450200Y9800D03*
X451300Y21700D03*
X464000Y275200D03*
X460400D03*
X452500D03*
X469000D03*
X472400Y275100D03*
X466500Y272800D03*
X472101Y266090D03*
X475500Y265900D03*
X479000D03*
X493000Y119299D03*
X495400Y183500D03*
X482400Y266200D03*
X498500Y88995D03*
X508000Y119500D03*
X511500D03*
X504400Y183400D03*
X510675Y209700D03*
X505315Y268500D03*
X497002Y275400D03*
X522280Y89810D03*
X515502Y88998D03*
X518902Y88987D03*
X518200Y183400D03*
X514800D03*
X528985Y89975D03*
X533267Y89634D03*
X539574Y88990D03*
X533000Y119500D03*
X536400D03*
X528100D03*
X528400Y145041D03*
X541550Y183550D03*
X534750Y183600D03*
X538150D03*
X530214Y183481D03*
X531000Y228350D03*
X552900Y89100D03*
X542950Y89400D03*
X555500Y183500D03*
X548354Y183600D03*
X551754D03*
X548300Y209700D03*
X566000Y89100D03*
X572845Y183300D03*
X566897Y183405D03*
X561900Y183600D03*
X564398Y183481D03*
X569395Y183300D03*
X558300Y210000D03*
X561000Y222700D03*
X561196Y227366D03*
X564200Y224000D03*
X575000Y89100D03*
X587500Y88913D03*
X578400Y89100D03*
X588600Y124700D03*
X584800Y183300D03*
X576295Y183400D03*
X588475Y183300D03*
X578795D03*
X573600Y190100D03*
X586800Y213200D03*
X583800Y207200D03*
X580350Y207250D03*
X599500Y87500D03*
X590898Y89045D03*
X593400Y126000D03*
X592200Y145000D03*
X595744Y145041D03*
X599150Y180300D03*
X593475Y183275D03*
X601750Y182500D03*
X594350Y187725D03*
X591850D03*
X591363Y208387D03*
X602800Y203225D03*
X601200Y207700D03*
X612120Y121750D03*
X608360Y121800D03*
X608300Y144890D03*
X618500Y159000D03*
X605600Y186650D03*
X609345Y190100D03*
X607500Y188300D03*
X616100Y197400D03*
X634000Y97500D03*
X630700Y100500D03*
X624726Y107395D03*
X621100Y124900D03*
X625500Y159000D03*
X629000D03*
X622000D03*
X633319Y155008D03*
X631900Y175850D03*
X634748Y177708D03*
X633100Y198300D03*
X626300Y198250D03*
X629700Y198300D03*
X622873Y204200D03*
X642823Y88477D03*
X640677Y91115D03*
X638500Y94000D03*
X635000Y110500D03*
X638000Y107400D03*
X648500Y144000D03*
X636719Y154972D03*
X643500Y155000D03*
X640110Y155272D03*
X640461Y181410D03*
X642600Y186400D03*
X646000D03*
X636500Y198300D03*
X653600Y122400D03*
X656477Y148033D03*
X656642Y151430D03*
X656200Y144000D03*
X650500Y155000D03*
X661000Y173800D03*
X657722Y193800D03*
X661600Y197300D03*
X654851Y191978D03*
X663800Y199900D03*
X673100Y179455D03*
X673044Y190456D03*
X668732Y204555D03*
X666446Y202037D03*
X682600Y114300D03*
X689400Y178900D03*
X689547Y175500D03*
X686700Y187400D03*
X687456Y183944D03*
X705145Y93500D03*
X707209Y97500D03*
X698970Y118149D03*
X699241Y114759D03*
X709500Y143500D03*
X709900Y139900D03*
X701245Y183800D03*
X718900Y94000D03*
X726800Y95500D03*
X724200Y108400D03*
X714000Y118500D03*
X727448Y128893D03*
X714900Y131900D03*
X718200Y147000D03*
Y150400D03*
X718825Y155453D03*
X712700Y155978D03*
X724400Y176025D03*
X725500Y195500D03*
X727400Y227400D03*
X736900Y98500D03*
X730200Y94900D03*
X742100Y118200D03*
X736300Y118000D03*
X729400Y120200D03*
X732000Y122700D03*
X728900Y132976D03*
X727800Y136600D03*
X740300Y164700D03*
X727800Y176600D03*
X733000Y176200D03*
X739900Y212800D03*
X731000Y210200D03*
X739800Y216300D03*
X750100Y16100D03*
X749500Y101500D03*
X751300Y118200D03*
X754000Y115100D03*
X748800Y115800D03*
X757900Y124700D03*
X743100Y195500D03*
X743000Y211000D03*
X744100Y221900D03*
X743800Y215900D03*
X758916Y104250D03*
X762304Y103957D03*
X765500Y112000D03*
X769800Y133000D03*
X759400Y131000D03*
X771300Y140200D03*
X766600Y139800D03*
X762000Y281000D03*
X765400D03*
X774500Y31307D03*
X778000D03*
X787600Y183300D03*
X787800Y179900D03*
X793000Y174500D03*
X805500Y128000D03*
G54D20*
X196800Y62600D03*
X199600Y160100D03*
X502500Y6200D03*
X538300Y15200D03*
X699000Y162255D03*
X756400Y110500D03*
X786500Y13500D03*
X782000Y137000D03*
X790500Y11000D03*
X799000Y121500D03*
Y125500D03*
X800400Y158500D03*
X799900Y168800D03*
X811000Y130000D03*
Y134000D03*
X809000Y149200D03*
X811000Y138000D03*
X811200Y141600D03*
X809500Y156900D03*
X809600Y160500D03*
X809700Y164300D03*
G54D13*
X15400Y118000D03*
X10900D03*
X15500Y122800D03*
X15000Y127500D03*
X11000Y122800D03*
X10500Y127500D03*
X11500Y163700D03*
Y159000D03*
X7000Y163700D03*
Y159000D03*
X33000Y105000D03*
X30200Y145000D03*
Y149200D03*
X34000Y161500D03*
X30300Y157600D03*
X30200Y153400D03*
X37500Y105000D03*
X42000D03*
X37500Y264000D03*
X63500Y43500D03*
Y57500D03*
Y48000D03*
Y52500D03*
X63200Y194900D03*
X68500Y47500D03*
X73500Y48000D03*
X68000Y52500D03*
X70900Y193800D03*
X82000Y177500D03*
X92800Y285600D03*
X104000Y106600D03*
Y115500D03*
Y111000D03*
X100000Y267400D03*
X100700Y262900D03*
X97500Y285450D03*
X102000D03*
X106500Y285550D03*
X110700D03*
X119400Y106700D03*
X123800Y102500D03*
X123900Y106700D03*
X119400Y102300D03*
Y115900D03*
Y111200D03*
X123900Y115900D03*
Y111200D03*
X113200Y146700D03*
X113100Y151000D03*
X117500Y146950D03*
X119000Y159100D03*
X114700Y158800D03*
X116500Y211200D03*
X134100Y96600D03*
X128500Y165000D03*
X129500Y252500D03*
X129000Y268000D03*
X166500Y241000D03*
X189000Y87700D03*
X192500Y161900D03*
X192600Y166700D03*
X201200Y164200D03*
X216261Y74846D03*
X212300Y157300D03*
X212600Y161500D03*
X217000Y252900D03*
X217200Y258000D03*
X226900Y133300D03*
X234525Y239250D03*
X229700Y234700D03*
X225300Y239200D03*
X234525Y243450D03*
X229725D03*
X225300Y243400D03*
X234525Y234800D03*
X225300D03*
X229675Y239000D03*
X221300Y255400D03*
X240130Y77300D03*
X236400Y95100D03*
X240565Y113365D03*
X249350Y199400D03*
X247500Y239250D03*
X243300Y235050D03*
X247500Y243450D03*
X243300D03*
X238900D03*
X243300Y239250D03*
X247500Y235050D03*
X238925Y235000D03*
Y239200D03*
X258400Y65600D03*
X252350Y202350D03*
X251700Y239250D03*
Y243450D03*
X253000Y267000D03*
X278200Y281350D03*
X294800Y94100D03*
X282686Y281336D03*
X339638Y67138D03*
X334500Y266300D03*
X334300Y270500D03*
X335700Y278751D03*
X331500D03*
X345089Y73089D03*
X353500Y71900D03*
X357000Y69500D03*
X349300Y83000D03*
X345100D03*
X354200Y76400D03*
X343600Y270500D03*
X371400Y42500D03*
X371500Y47000D03*
X359800Y72700D03*
X362700Y69600D03*
X380000Y38100D03*
X375600Y42500D03*
X380300D03*
X375700Y47000D03*
X380295Y46779D03*
X496711Y248999D03*
X527000Y225500D03*
X598814Y240095D03*
X615100Y238900D03*
X623900Y239600D03*
X646000Y46007D03*
X640000D03*
X654500Y46107D03*
X659811Y260757D03*
X657500Y258400D03*
X661308Y263698D03*
X655500Y270500D03*
X657787Y264179D03*
X656000Y261400D03*
X655523Y266616D03*
X658667Y267622D03*
X721200Y65100D03*
X732000Y63500D03*
X753500Y24007D03*
Y20007D03*
Y28507D03*
X755500Y16000D03*
X770500Y13007D03*
X767500Y24007D03*
X760500Y29000D03*
X761000Y16007D03*
X767500Y28507D03*
Y19507D03*
X764200Y44200D03*
X767500Y33207D03*
X759000Y37507D03*
X764500Y54000D03*
X764300Y49200D03*
X769500Y50000D03*
X761000Y58500D03*
X787500Y93000D03*
X783000D03*
X785830Y188700D03*
X785400Y202800D03*
X789000Y204979D03*
X789200Y214200D03*
Y209800D03*
X784500Y222500D03*
X789000Y223500D03*
X789200Y218700D03*
X786000Y228000D03*
Y232400D03*
X786200Y236900D03*
X786300Y241500D03*
X785000Y245800D03*
Y250200D03*
Y254900D03*
X792000Y83000D03*
X796500D03*
X792000Y87700D03*
X796500D03*
X799200Y98600D03*
X803100Y106000D03*
X799200Y102800D03*
X799000Y107100D03*
X803500Y116700D03*
Y112500D03*
X799000Y116100D03*
Y111900D03*
X789910Y187679D03*
X794110D03*
X798310Y187779D03*
X793500Y204979D03*
Y223500D03*
X793200Y228400D03*
Y232600D03*
Y237200D03*
Y242400D03*
X793300Y247200D03*
X795300Y260800D03*
X795400Y251700D03*
X795300Y256500D03*
Y265000D03*
X810100Y275000D03*
X812035Y271067D03*
X810100Y267339D03*
X812000Y263500D03*
G54D18*
X42717Y270472D03*
X235630Y75590D03*
X492520Y262598D03*
D03*
X761417Y22798D03*
D03*
X794032Y27032D03*
X804032Y37032D03*
Y47032D03*
X794032Y37032D03*
Y47032D03*
X804032Y57032D03*
X794032D03*
Y67032D03*
G54D22*
X235630Y174016D03*
X498425Y22798D03*
D03*
X755512Y262598D03*
D03*
G54D24*
X303610Y110800D03*
X309000Y114700D03*
X306700D03*
X309194Y117700D03*
X306994Y117725D03*
X304149Y128349D03*
X307854Y130539D03*
X309700Y122796D03*
X309500Y132925D03*
X307298Y132697D03*
X307500Y122700D03*
X305050Y151150D03*
X309000Y137600D03*
X306961Y153717D03*
X306696Y158610D03*
X309000Y158806D03*
X309220Y153698D03*
X305800Y195400D03*
X303500D03*
X303480Y189100D03*
X301300Y188700D03*
X309700Y187997D03*
X307500Y188000D03*
X317641Y90956D03*
X325081Y100631D03*
X322075Y100650D03*
X323120Y92400D03*
X319520Y92419D03*
X318900Y98000D03*
X317600Y93625D03*
X326162Y91438D03*
X315950Y98650D03*
X320992Y112180D03*
X319096Y113300D03*
X319418Y123225D03*
X315451Y123219D03*
X323900Y129900D03*
X325418Y127349D03*
X325746Y133702D03*
X323300Y147046D03*
X326322Y138434D03*
X325763Y141958D03*
X325200Y149319D03*
X319704Y162804D03*
X323000Y153900D03*
X324029Y166384D03*
X326234Y153969D03*
X323500Y180063D03*
X323121Y182913D03*
X326408Y182292D03*
X316844Y196010D03*
X319801Y194890D03*
X326550Y191600D03*
X322256Y198618D03*
X323331Y196696D03*
X325642Y202325D03*
X321600Y208700D03*
Y211000D03*
X317200Y213100D03*
Y215300D03*
X316000Y237700D03*
X319100D03*
X329300Y87300D03*
X331200Y88600D03*
X330100Y100200D03*
Y98000D03*
X336750Y93500D03*
Y95704D03*
X328000Y92700D03*
X330900Y93400D03*
X333313Y103693D03*
X329415Y119923D03*
X333601Y120500D03*
X333534Y118040D03*
X333434Y106668D03*
X341200Y112569D03*
X338768Y116755D03*
Y119755D03*
X329308Y122386D03*
X338329Y135665D03*
X329031Y125428D03*
X335303Y135178D03*
X336900Y127600D03*
X333977Y127678D03*
X327854Y130434D03*
X338470Y138177D03*
X335450Y150900D03*
X327963Y142008D03*
X335514Y138220D03*
X338320Y141300D03*
X327390Y149106D03*
X336920Y146130D03*
X329421Y138228D03*
X327696Y146108D03*
X330163Y142008D03*
X332478Y138255D03*
X341342Y138224D03*
X333750Y145950D03*
X339491Y143163D03*
X329800Y150800D03*
X332000D03*
X330300Y158546D03*
X339784Y161847D03*
X335499Y153846D03*
X327800Y161500D03*
X336900Y161600D03*
X336800Y164434D03*
X341390Y153991D03*
X329161Y153830D03*
X335964Y158512D03*
X341400Y156700D03*
X331000Y164500D03*
X330900Y161700D03*
X333000Y158300D03*
X339747Y164478D03*
X339300Y174100D03*
X330821Y177402D03*
X329442Y169463D03*
X327708Y177241D03*
X332353Y169522D03*
X337000Y174102D03*
X327600Y174174D03*
X330027Y174119D03*
X334700Y174100D03*
X336915Y177423D03*
X337863Y180545D03*
X330280Y180900D03*
X332500D03*
X335400Y196300D03*
X337800Y189200D03*
X326850Y193900D03*
X329972Y196400D03*
Y193559D03*
X333996Y192063D03*
X334707Y189383D03*
X337800Y192200D03*
X329313Y188000D03*
X335739Y199317D03*
X336500Y204600D03*
X338926Y211674D03*
X338967Y209455D03*
X331658Y212660D03*
X327216Y203902D03*
X328510Y218320D03*
X327024Y220024D03*
X337307Y217961D03*
X331616Y214860D03*
X337341Y215731D03*
X328945Y235846D03*
X331142Y233658D03*
X346596Y118163D03*
Y115163D03*
X343570Y112561D03*
X346495Y130000D03*
X349149Y124141D03*
X351500Y136000D03*
X343000Y126200D03*
X343146Y128473D03*
X347641Y133479D03*
X342533Y133822D03*
X357300Y128600D03*
X355400Y137100D03*
X354300Y128600D03*
X346300Y143000D03*
X355447Y146528D03*
X344500Y141700D03*
X348675Y143326D03*
X348743Y146072D03*
X346000Y146043D03*
X346450Y149120D03*
X348432Y164844D03*
X346944Y156775D03*
X350550Y153280D03*
X344300Y153800D03*
X344090Y156690D03*
X352000Y162000D03*
X348700Y161700D03*
X351600Y164300D03*
X355400Y152900D03*
X350700Y155600D03*
X345900Y161700D03*
X342188Y183361D03*
X355300Y174600D03*
X347200Y174300D03*
X344165Y169466D03*
X352200Y171800D03*
X347500Y169500D03*
X351600Y169600D03*
X353302Y182993D03*
X342233Y185639D03*
X356900Y186100D03*
X349600Y194800D03*
X342339Y192225D03*
X342342Y190024D03*
X349100Y191900D03*
X353625Y195045D03*
Y192045D03*
X356600Y195700D03*
X356700Y193300D03*
X345503Y193474D03*
X345500Y190500D03*
X349100Y189700D03*
X353342Y186124D03*
X345500Y184500D03*
X345631Y187420D03*
X353594Y210707D03*
X347593Y210277D03*
X353385Y212898D03*
X343242Y213690D03*
X347664Y212476D03*
X343198Y215910D03*
X371900Y85400D03*
X364800Y91200D03*
X368600Y90700D03*
X361200Y90200D03*
X371950Y92500D03*
X364874Y98250D03*
X362803Y106035D03*
X357900Y99200D03*
X368600Y97500D03*
X357721Y91779D03*
X361200Y97500D03*
X365316Y108130D03*
X372700Y119663D03*
X370100Y119563D03*
X370000Y116563D03*
X362111Y127142D03*
X362120Y124153D03*
X359421Y127128D03*
Y124008D03*
X372821Y125628D03*
X370121Y125528D03*
X367321Y122528D03*
X368026Y137118D03*
X364700Y134000D03*
X367992Y133982D03*
X359300Y130000D03*
X367900Y152550D03*
X368000Y146500D03*
X361700Y143300D03*
X364886Y140268D03*
X368026D03*
Y143418D03*
X364621Y143328D03*
X361500Y149500D03*
X368026Y149718D03*
X368100Y165300D03*
X364600D03*
X367950Y159200D03*
X371157Y162320D03*
X371176Y158940D03*
X358477Y159300D03*
X361600Y159250D03*
X368100Y162200D03*
X358342Y165324D03*
X358576Y162090D03*
X358500Y155700D03*
X371100Y168700D03*
X364600Y174800D03*
X361500Y175000D03*
Y168500D03*
X368000D03*
X367906Y171458D03*
X364600Y171600D03*
X364607Y177103D03*
X370900Y171700D03*
X361200Y178500D03*
X361292Y181409D03*
X372400Y179100D03*
X369021Y180128D03*
X372600Y181400D03*
X361400Y187600D03*
X368455Y196455D03*
X371299Y196008D03*
X364792Y188743D03*
X364600Y186138D03*
X364895Y190941D03*
X369106Y191903D03*
X369200Y189100D03*
X361257Y193524D03*
Y190700D03*
X364947Y193141D03*
X361300Y184500D03*
X359222Y197700D03*
X369009Y186191D03*
X372700Y213700D03*
X369450Y212040D03*
X358498Y210220D03*
X358382Y212427D03*
X371100Y199500D03*
X365250Y208600D03*
X372800Y221600D03*
X369580Y218800D03*
Y215400D03*
X357966Y217516D03*
X359827Y216341D03*
X383350Y83350D03*
X383450Y90500D03*
X387200D03*
X387100Y83500D03*
X375800D03*
Y90500D03*
X379500Y83302D03*
Y90600D03*
X381600Y119900D03*
X381900Y113000D03*
X382596Y108600D03*
X385600Y116500D03*
X385200Y113137D03*
X385721Y119528D03*
X385479Y125569D03*
X381500Y123200D03*
X381600Y126427D03*
X385523Y122532D03*
X386708Y137118D03*
X383567Y137096D03*
X380475Y137016D03*
X380443Y130102D03*
X374200Y136994D03*
X380398Y146568D03*
X383548D03*
X374200Y140144D03*
X380400Y152700D03*
X383575Y149603D03*
X380522Y149564D03*
X386853Y149640D03*
X377476Y149688D03*
X374200Y149494D03*
X374100Y159150D03*
X386800Y165300D03*
X380398Y165240D03*
X383781Y165235D03*
X386777Y162155D03*
X387000Y155850D03*
X386777Y159005D03*
X380500Y162025D03*
X383700Y162199D03*
X383500Y159000D03*
X374300Y155800D03*
X377500Y165240D03*
Y156000D03*
X384740Y180080D03*
X381720Y180220D03*
X381800Y183300D03*
X380540Y177370D03*
X380500Y168500D03*
X383693Y171424D03*
X383548Y168390D03*
X386600Y174900D03*
X380477Y171605D03*
X376830Y175640D03*
X376800Y178600D03*
X376742Y181524D03*
X381460Y195610D03*
X384390Y196470D03*
X381140Y187960D03*
X381280Y191550D03*
X384708Y188910D03*
X384600Y186100D03*
X376800Y193500D03*
X376900Y196600D03*
X373922Y193103D03*
X374000Y190350D03*
X379750Y213500D03*
X376300Y211000D03*
Y213700D03*
X382600Y222600D03*
X382750Y229000D03*
X379700Y219200D03*
X385947Y226500D03*
X385900Y218400D03*
X376300Y216200D03*
X379700Y216500D03*
X372950Y217400D03*
X390700Y89300D03*
X403726Y83826D03*
X403700Y90200D03*
X397300Y89168D03*
X400400Y92200D03*
Y98500D03*
X390750Y96500D03*
X394100Y91400D03*
Y99000D03*
X397100Y96600D03*
X393331Y118043D03*
X393351Y115107D03*
X397650Y115500D03*
X401749Y112418D03*
X401159Y119636D03*
X401353Y116562D03*
X396276Y120948D03*
X396251Y117999D03*
X393653Y121122D03*
X389700Y112363D03*
X398500Y125604D03*
X398512Y122815D03*
X401500Y125600D03*
X393482Y123982D03*
X396700Y128000D03*
X389914Y124536D03*
X393561Y127130D03*
X401500Y122600D03*
X401256Y128755D03*
X397800Y130000D03*
X390100Y127600D03*
X390205Y133858D03*
X392998Y133968D03*
X396148D03*
X396321Y136987D03*
X402561Y137000D03*
X399298Y137118D03*
X392998D03*
X389848D03*
X402400Y140163D03*
X396148Y140268D03*
X399298D03*
X389848Y146568D03*
X393204Y146436D03*
X392998Y165240D03*
X396148Y155790D03*
X393208D03*
X399298Y165240D03*
X392599Y181686D03*
X400252Y182966D03*
X403600Y182400D03*
Y180200D03*
X402540Y171760D03*
X399300Y168400D03*
X402600Y174611D03*
X395573Y175400D03*
X393077Y168455D03*
X399385Y171686D03*
X396225D03*
X390025Y174672D03*
X393085Y171686D03*
Y174836D03*
X400352Y180171D03*
X397100Y181000D03*
X400301Y186099D03*
X397805Y192061D03*
X392600Y190600D03*
X396200Y194700D03*
X392624Y184537D03*
X389500Y193600D03*
X397307Y186607D03*
X395600Y184100D03*
Y190300D03*
X392700Y193563D03*
X403022Y192094D03*
X402967Y195005D03*
X389484Y190442D03*
X389300Y187700D03*
X402962Y189014D03*
X392596Y187541D03*
X397728Y189053D03*
X395641Y188045D03*
X392100Y213700D03*
X395700Y213600D03*
X389100Y224000D03*
X399700Y225000D03*
Y216400D03*
X395600Y224400D03*
X395700Y217000D03*
X391950Y220800D03*
X389150Y230300D03*
X407500Y84000D03*
X407400Y91000D03*
X411300Y85600D03*
X414722Y90250D03*
X418300Y91300D03*
X418400Y98150D03*
X411000Y92100D03*
X414622Y98000D03*
X404529Y118507D03*
X405900Y121700D03*
X409110Y114910D03*
X405200Y115343D03*
X412462Y115713D03*
X409196Y118195D03*
X416904Y119591D03*
X416922Y116613D03*
X413100Y121800D03*
X409110Y120910D03*
X404900Y124600D03*
X416000Y135983D03*
X415000Y131400D03*
X408956Y130064D03*
X418500Y128200D03*
X415100Y127900D03*
X406200Y127400D03*
X416851Y122600D03*
X412600Y124100D03*
X412462Y126300D03*
X404400Y128900D03*
X414900Y147000D03*
X417900Y146900D03*
X408800Y147000D03*
X411900Y146800D03*
X413300Y139100D03*
X413400Y142700D03*
X418000Y142500D03*
X418439Y167118D03*
X414800Y162600D03*
X411800Y162700D03*
X414572Y165913D03*
X411356Y165732D03*
X410100Y157700D03*
X416400Y155000D03*
X409300Y167163D03*
X407100Y167429D03*
X418600Y182800D03*
X414960Y178130D03*
X414950Y181460D03*
X411260Y178090D03*
X411553Y181222D03*
X416400Y170300D03*
X413265Y170423D03*
X410620Y173300D03*
X405100Y178500D03*
X416315Y183219D03*
X415992Y189254D03*
Y186205D03*
X419097Y189563D03*
X416500Y195563D03*
X408242Y184624D03*
X405231Y184976D03*
X408200Y190500D03*
X408100Y193600D03*
X412000Y187500D03*
X412500Y194900D03*
X412100Y190400D03*
X418800Y196700D03*
X416139Y192007D03*
X405102Y187874D03*
X412200Y192600D03*
X416900Y200100D03*
X408200Y226900D03*
X408100Y220500D03*
X404400Y228600D03*
Y222300D03*
X415600Y222700D03*
X415800Y215900D03*
X412050Y225100D03*
X412100Y218400D03*
X422078Y97678D03*
X422000Y91300D03*
X427560Y104770D03*
X429105Y106337D03*
X426800Y97850D03*
X429500Y93800D03*
X428100Y120000D03*
X424900Y121213D03*
X420600Y118300D03*
X420672Y120600D03*
X422042Y115224D03*
X424700Y115000D03*
X427900Y114300D03*
X428100Y116500D03*
X427500Y112091D03*
X425200Y118823D03*
X431188Y116105D03*
X430342Y119724D03*
X428255Y126236D03*
X425000Y135350D03*
X419500Y136400D03*
X430100Y131500D03*
X431700Y128300D03*
X423500Y128200D03*
X427000Y128050D03*
X423900Y131500D03*
X420942Y131324D03*
X422300Y126300D03*
X427600Y143841D03*
X421500Y142400D03*
X426900Y147100D03*
X431100Y145500D03*
X424856Y142270D03*
X422400Y139000D03*
X420861Y149687D03*
Y146923D03*
X430694Y142275D03*
X428390Y139059D03*
X423945Y165221D03*
X421710Y167230D03*
X431130Y166660D03*
X428238Y167709D03*
X420804Y162659D03*
X420900Y160037D03*
X425500Y154737D03*
X428400D03*
X434500Y160037D03*
X430360Y181350D03*
X430340Y177620D03*
X423642Y181374D03*
X426970Y178310D03*
X425400Y170240D03*
X428500Y173120D03*
X422337Y170575D03*
X425427Y173113D03*
X419453Y173187D03*
X420922Y178117D03*
X423842Y178274D03*
X428431Y170264D03*
X432100Y190400D03*
X429100Y189696D03*
X426173Y190784D03*
X428830Y195379D03*
X422152Y189600D03*
X420800Y193100D03*
X421171Y196496D03*
X431270Y193425D03*
X425500Y186045D03*
X423966Y190846D03*
X423800Y196500D03*
X433842Y197021D03*
X421848Y186550D03*
X428400Y185900D03*
X420975Y211300D03*
X427900Y202800D03*
X424832Y200174D03*
X421811Y202603D03*
X426311Y204399D03*
X419550Y222700D03*
X419600Y216200D03*
X437400Y121600D03*
X442842Y120824D03*
X438700Y112900D03*
X438500Y116400D03*
X439400Y120100D03*
X434960Y114529D03*
X444242Y124324D03*
X435442Y124024D03*
X437800Y128100D03*
X439275Y124197D03*
X443400Y148900D03*
X437472Y152501D03*
X434834Y163817D03*
X439600Y153800D03*
X438742Y197224D03*
X435642Y194824D03*
X437921Y192956D03*
X459800Y118800D03*
X453000Y118700D03*
X459700Y129900D03*
X452200Y129800D03*
X463100Y133700D03*
X456000Y133500D03*
X460100Y123100D03*
X453000Y123300D03*
X463200Y126200D03*
X456500Y126100D03*
X461200Y167400D03*
X454200D03*
X464300Y181800D03*
X458000Y171100D03*
X451000D03*
X460000Y174900D03*
X453000D03*
X457400Y197000D03*
X450400D03*
X462500Y189000D03*
X460400Y193300D03*
X453400D03*
X459500Y200700D03*
X452500D03*
X473900Y178200D03*
X466900D03*
X471300Y181800D03*
X473100Y185500D03*
X466000D03*
X469500Y189000D03*
X504000Y12507D03*
X508700Y14607D03*
X511589Y30295D03*
X507839Y30362D03*
X506496Y272500D03*
X523453Y12360D03*
X511800Y12507D03*
X520700Y14807D03*
X518769Y22907D03*
X515484D03*
X525753Y30893D03*
X522733Y32832D03*
X511640Y255956D03*
X514137Y256089D03*
X522908Y255117D03*
X526715Y254700D03*
X511736Y273001D03*
X514900Y271350D03*
X522992Y270700D03*
X525845Y272863D03*
X517846Y262489D03*
X521131D03*
X528525Y12549D03*
X542100Y15107D03*
X530700Y15407D03*
X536485Y22907D03*
X533200D03*
X542407Y30882D03*
X532350Y30807D03*
X529120Y32575D03*
X530015Y255000D03*
X531775Y252231D03*
X541005Y254800D03*
X530900Y273000D03*
X534100Y270700D03*
X541500Y270900D03*
X535562Y262489D03*
X538847D03*
X550000Y12507D03*
X544860Y12407D03*
X552800Y14807D03*
X557745Y22907D03*
X554460D03*
X553079Y30712D03*
X549500Y31607D03*
X545928Y31047D03*
X544800Y255100D03*
X550200Y255500D03*
X551000Y252056D03*
X544292Y273128D03*
X548800Y271000D03*
X551937Y272789D03*
X555641Y262489D03*
X568555Y12407D03*
X561200Y12507D03*
X571600Y14207D03*
X564400Y14307D03*
X570852Y33204D03*
X569800Y29807D03*
X565091Y30815D03*
X561456Y30902D03*
X561419Y254850D03*
X565054Y254773D03*
X568327Y253348D03*
X571867Y254685D03*
X560600Y270300D03*
X564100Y271100D03*
X567800Y270500D03*
X570200Y273100D03*
X558926Y262489D03*
X587940Y12417D03*
X582655Y12407D03*
X579800Y14807D03*
X577824Y22907D03*
X574539D03*
X585179Y30867D03*
X581450Y30707D03*
X587700Y255300D03*
X579205Y254850D03*
X582200Y252206D03*
X587642D03*
X580200Y273000D03*
X582600Y270300D03*
X588036Y273089D03*
X588400Y270300D03*
X573357Y262489D03*
X576642D03*
X594600Y6707D03*
X601704Y22907D03*
X594400Y36207D03*
X589300Y33007D03*
X594600Y260000D03*
X591300Y255010D03*
X590837Y259889D03*
X598398Y260199D03*
X591342Y252206D03*
X603187Y252056D03*
X589500Y257100D03*
X594500Y265200D03*
X591500Y270100D03*
X591536Y273000D03*
X590700Y264833D03*
X598300Y265400D03*
X589900Y268133D03*
X602450Y272900D03*
X598418Y262699D03*
X590322Y262361D03*
X594559Y262559D03*
X595386Y272932D03*
X610952Y12307D03*
X616600D03*
X614700Y14107D03*
X615852Y19807D03*
X615907Y24856D03*
X607300Y14507D03*
X616707Y15616D03*
X604989Y22907D03*
X615951Y22356D03*
X612000Y17407D03*
X610944Y33333D03*
X607800Y30407D03*
X618900Y33290D03*
X615103Y30690D03*
X615044Y33190D03*
X618877Y30790D03*
X619382Y260089D03*
X615532Y259700D03*
X611706Y259387D03*
X606700Y255600D03*
X604074Y254394D03*
X609500Y254900D03*
X609937Y252106D03*
X608700Y257300D03*
X611845Y253723D03*
X615537Y264789D03*
X619100Y265300D03*
X611536Y264385D03*
X609896Y272889D03*
X608996Y270206D03*
X605100Y270100D03*
X605065Y272967D03*
X611593Y261885D03*
X606200Y267800D03*
X615430Y262213D03*
X612393Y273026D03*
X619180Y262689D03*
X633500Y12406D03*
X624000D03*
X623532Y20007D03*
X623555Y25107D03*
X619607Y19807D03*
X627255Y25107D03*
X627231Y19907D03*
X630955Y25207D03*
X631000Y20107D03*
X634555Y25307D03*
X634757Y20207D03*
X619730Y24864D03*
X634757Y22707D03*
X623480Y22564D03*
X631007Y22707D03*
X619700Y22307D03*
X627257Y22407D03*
X624100Y33190D03*
X633449D03*
X630432Y260100D03*
X626682Y260300D03*
X622933Y260189D03*
X634207Y260300D03*
X630455Y265400D03*
X634280Y265332D03*
X626651Y265489D03*
X622899Y265189D03*
X629937Y272990D03*
X630457Y262832D03*
X626680Y262989D03*
X634280Y262832D03*
X620437Y272990D03*
X622930Y262689D03*
X644193Y12907D03*
X648800Y12707D03*
X641745Y12367D03*
X638400Y20607D03*
X638290Y25674D03*
X642246Y25807D03*
X642451Y20707D03*
X645300Y15507D03*
X648400Y15490D03*
X645200Y27707D03*
X646800Y17607D03*
X642257Y23307D03*
X638507Y23183D03*
X647000Y29607D03*
X649550Y30807D03*
X643700Y33290D03*
X644100Y30307D03*
X650200Y33307D03*
X641900Y31507D03*
X638032Y260342D03*
X642802Y252186D03*
X645920Y254130D03*
X635043Y252106D03*
X638900Y254809D03*
X635197Y254602D03*
X638893Y252206D03*
X638090Y265340D03*
X642937Y273089D03*
X646360Y271530D03*
X637288Y270100D03*
X637337Y272944D03*
X648948Y262489D03*
X637987Y262842D03*
X644550Y267170D03*
X639500Y268800D03*
X662359Y12379D03*
X657897Y12504D03*
X651316Y12360D03*
X659400Y25907D03*
Y20474D03*
X662192Y14874D03*
X663202Y25973D03*
X655602Y25223D03*
X663200Y20956D03*
X655700Y20225D03*
X664212Y16356D03*
X663300Y23454D03*
X662916Y28457D03*
X655592Y22723D03*
X659400Y23207D03*
X662503Y33207D03*
X657900Y30690D03*
X664678Y30307D03*
X661708Y30699D03*
X657900Y33190D03*
X659437Y246389D03*
X665500Y252189D03*
X659500Y274000D03*
X665100Y272700D03*
X652233Y262489D03*
X671290Y12457D03*
X665901Y12307D03*
X674320Y14219D03*
X666175Y14807D03*
X680580Y22807D03*
X677295D03*
X669600Y17907D03*
X674400Y31307D03*
X671295Y33190D03*
X670200Y254700D03*
X673770Y254752D03*
X669700Y270900D03*
X672800Y272700D03*
X676113Y262489D03*
X679398D03*
X690102Y12502D03*
X684760Y12256D03*
X692200Y15357D03*
X682013Y14848D03*
X695029Y22853D03*
X693300Y30607D03*
X689624Y30383D03*
X685700Y30807D03*
X681900Y30907D03*
X682800Y254900D03*
X685382Y252200D03*
X688800Y254600D03*
X692250Y255700D03*
X682481Y270700D03*
X685100Y273100D03*
X689700Y270800D03*
X692537Y272989D03*
X696192Y262489D03*
X709000Y12407D03*
X702000Y12607D03*
X705031Y14515D03*
X698277Y22855D03*
X708900Y30407D03*
X704430Y33313D03*
X701800Y30807D03*
X701649Y255049D03*
X704178Y252189D03*
X707800Y255000D03*
X711400Y255072D03*
X701300Y270777D03*
X704277Y272989D03*
X709400Y272600D03*
X699477Y262489D03*
X723586Y14080D03*
X712182Y14124D03*
X720100Y14707D03*
X718375Y22907D03*
X715090D03*
X727000Y30407D03*
X723500Y29907D03*
X721747Y32954D03*
X712400Y30807D03*
X721500Y255000D03*
X724374Y254515D03*
X712200Y270500D03*
X722400Y270800D03*
X725300Y272800D03*
X717452Y262489D03*
X720737D03*
X715900Y270000D03*
X742200Y12407D03*
X728010Y12857D03*
X739000Y14407D03*
X731169Y14584D03*
X736091Y23607D03*
X732806D03*
X742100Y33007D03*
X740200Y29907D03*
X730500D03*
X730400Y255400D03*
X732200Y252200D03*
X741560Y255000D03*
X730400Y272850D03*
X732740Y270200D03*
X741200Y270500D03*
X735168Y262489D03*
X738453D03*
X744900Y20500D03*
X745000Y23000D03*
X747441Y33007D03*
X744437Y252189D03*
X744200Y272600D03*
X753000Y272100D03*
G54D17*
X42717Y191732D03*
G54D19*
X144000Y67875D03*
Y147125D03*
X276811Y263386D03*
X296811D03*
X457913Y45276D03*
X477913D03*
G54D14*
X13000Y137000D03*
Y141500D03*
X13100Y150600D03*
X13000Y146000D03*
X45500Y118000D03*
X76200Y187200D03*
X86500Y177500D03*
X90700Y177050D03*
X122250Y228750D03*
Y233000D03*
Y237300D03*
Y241500D03*
X133941Y208863D03*
X131003Y205766D03*
X138100Y208100D03*
X136500Y272500D03*
X158700Y213800D03*
X309100Y206800D03*
X315400Y110800D03*
X311600D03*
X322691Y136023D03*
X323550Y142104D03*
X319401Y149354D03*
X317698Y152311D03*
X315384Y166733D03*
X324953Y161722D03*
X323165Y171937D03*
X324436Y175705D03*
X326399Y169401D03*
X319942Y180524D03*
X320029Y184300D03*
X318700Y207800D03*
X311600Y207600D03*
X328000Y97100D03*
X334850Y96900D03*
X335500Y91600D03*
X339500Y102000D03*
X332600Y101400D03*
X333551Y115090D03*
X333416Y108899D03*
X341309Y135651D03*
X329693Y134428D03*
X331290Y125810D03*
X330870Y130540D03*
X336190Y141970D03*
X330796Y146221D03*
X333742Y161624D03*
X332185Y153806D03*
X334470Y164760D03*
X335400Y169600D03*
X333842Y177224D03*
X332300Y173900D03*
X339875Y177303D03*
X334715Y180900D03*
X329028Y199931D03*
X344523Y98477D03*
X344500Y94000D03*
X347230Y100190D03*
X355175Y108212D03*
X348076Y108910D03*
X354333Y125665D03*
X343000Y124000D03*
X342880Y146180D03*
X350800Y138300D03*
X355342Y143424D03*
X348743Y149100D03*
X342716Y161593D03*
X345562Y178700D03*
X349751Y187241D03*
X356800Y191000D03*
X361141Y104099D03*
X369997Y113706D03*
X358000Y115500D03*
X364600Y137063D03*
X367221Y125428D03*
X370000Y122563D03*
X367121Y128628D03*
X362111Y130128D03*
X361726Y140268D03*
X361700Y146549D03*
X359750Y208390D03*
X359910Y214100D03*
X377818Y115008D03*
X377800Y124163D03*
X384650Y183170D03*
X380510Y185500D03*
X384684Y191950D03*
X382471Y199843D03*
X385900Y222600D03*
X382700Y226000D03*
X396600Y112463D03*
X390683Y108042D03*
X400700Y108800D03*
X389200Y227400D03*
X392000Y217200D03*
X395700Y220600D03*
X399800D03*
X414672Y94500D03*
X417800Y100400D03*
X418300Y94800D03*
X407550Y100196D03*
X412100Y135600D03*
X417753Y131322D03*
X415700Y143100D03*
X410302Y141864D03*
X406042Y147025D03*
X415100Y149800D03*
X407399Y142561D03*
X408837Y149809D03*
X413314Y154908D03*
X410272Y154794D03*
X408200Y223800D03*
X412000Y222000D03*
X404400Y225300D03*
X422050Y94800D03*
X430302Y112098D03*
X419596Y113463D03*
X431504Y126061D03*
X424982Y126500D03*
X432542Y136898D03*
X426982Y131334D03*
X423496Y144000D03*
X428363Y141756D03*
X426000Y167370D03*
X430542Y160753D03*
X430600Y164513D03*
X422363Y154700D03*
X444578Y106201D03*
X442378Y106198D03*
X440178Y106200D03*
X443443Y144757D03*
X437398Y146257D03*
X435004Y142110D03*
G54D23*
X305900Y121151D03*
X311200Y114800D03*
X311410Y118110D03*
X312000Y122600D03*
X312917Y133440D03*
X312829Y181940D03*
X345837Y199887D03*
G54D12*
X14000Y104500D03*
X14400Y98000D03*
X14000Y109500D03*
X14500Y198000D03*
X17301Y212401D03*
X4500Y228900D03*
X4600Y223100D03*
X17300Y218307D03*
X10000Y229500D03*
X16400Y224212D03*
X4500Y234800D03*
X4400Y245100D03*
X16118Y230118D03*
X10194Y243106D03*
X9500Y234200D03*
X16899Y241929D03*
X16300Y236023D03*
X4400Y256700D03*
X10190Y258510D03*
X10194Y254917D03*
X10190Y246699D03*
X16899Y247834D03*
Y253740D03*
Y259645D03*
X5000Y275000D03*
X12600Y266900D03*
X7600Y268100D03*
X16899Y265551D03*
X15300Y285800D03*
X4900Y285700D03*
X23400Y81550D03*
X25000Y77300D03*
X32800Y120400D03*
X25800Y120300D03*
X29200D03*
X30000Y196200D03*
X21900Y205400D03*
X31500Y207500D03*
X25200Y286000D03*
X40500Y127700D03*
X38500Y148000D03*
X48500D03*
X41000Y152300D03*
Y143300D03*
X46000D03*
Y152300D03*
X43500Y148000D03*
Y138500D03*
X48500D03*
X38500D03*
X45800Y158100D03*
X34800Y198800D03*
Y203700D03*
X37600Y212700D03*
Y207800D03*
X34500Y216000D03*
X40400Y217100D03*
X40700Y224000D03*
X40200Y238300D03*
Y231300D03*
Y245300D03*
X40500Y260000D03*
X40600Y252500D03*
X52500Y96500D03*
Y106500D03*
X57500Y96500D03*
X60000Y101500D03*
X50000D03*
X55000D03*
X57500Y106500D03*
X60000Y111300D03*
X50000D03*
X55000D03*
X50500Y160000D03*
X54700Y192200D03*
X52700Y184800D03*
X62800Y184300D03*
X57600Y214200D03*
X74000Y37642D03*
X66500D03*
X78300Y64300D03*
X72137Y210237D03*
X79500Y230000D03*
X78700Y259800D03*
X67600Y255800D03*
X66300Y259300D03*
X67000Y263200D03*
X82211Y37747D03*
X89862Y37849D03*
X89400Y58200D03*
X83600Y57600D03*
X95500Y93500D03*
X94000Y137500D03*
Y133000D03*
X84500Y230000D03*
X89500D03*
X84500Y225000D03*
Y235000D03*
X91400Y270300D03*
X98500Y37642D03*
X105794Y37692D03*
X104400Y57700D03*
X96800Y53300D03*
X99500Y91500D03*
Y96000D03*
X104000Y92000D03*
Y96500D03*
X105775Y137349D03*
X103175Y134050D03*
X98500Y137500D03*
X109000Y134050D03*
X98500Y133000D03*
X95700Y197200D03*
X99600Y225700D03*
X99328Y235370D03*
X109000Y231400D03*
X113605Y37665D03*
X121500Y37642D03*
X121400Y60100D03*
X114800Y60700D03*
X114500Y134050D03*
X120500Y139000D03*
X125000Y178000D03*
X119760Y191419D03*
X115760D03*
X123760D03*
X129336Y37652D03*
X137300Y37642D03*
X136400Y60600D03*
X130400D03*
X136500Y101523D03*
X136770Y113000D03*
X136500Y126300D03*
X132700Y158600D03*
X153088Y37653D03*
X145070Y37642D03*
X143700Y54503D03*
X154615Y54500D03*
X152811Y84300D03*
X157175Y115462D03*
X150670Y112100D03*
Y122300D03*
X150500Y183000D03*
X157000Y169194D03*
X168791Y37689D03*
X160898Y37704D03*
X169600Y53000D03*
X159957Y51932D03*
X167500Y68000D03*
X158105Y96775D03*
X171800Y126600D03*
X162900Y152200D03*
X167602Y160684D03*
X169800Y181448D03*
X165700Y203400D03*
X162000Y226000D03*
X167000D03*
Y221500D03*
X162000D03*
Y230500D03*
X167000D03*
X162000Y235000D03*
X176640Y37699D03*
X184500Y37700D03*
X185000Y51600D03*
X175758Y52879D03*
X184300Y78500D03*
X177200Y130575D03*
X187597Y133697D03*
X176400Y175700D03*
X185546Y192509D03*
X180546D03*
X175546D03*
X177500Y209500D03*
X176800Y241600D03*
X186500Y276500D03*
Y281000D03*
X192400Y37642D03*
X200300D03*
X191700Y52100D03*
X201500Y54500D03*
X196900Y68700D03*
X198500Y83800D03*
X193485Y83724D03*
X202500Y97000D03*
X188363Y116137D03*
X201252Y137766D03*
X192237Y147300D03*
X199900Y154200D03*
X200900Y177000D03*
X202800Y191400D03*
X196000Y186897D03*
X191400Y206100D03*
X203100Y252900D03*
X191100Y276600D03*
X190900Y280800D03*
X207600Y37642D03*
X216085Y37649D03*
X210900Y57600D03*
X213558Y98500D03*
X205689Y112879D03*
X205850Y118175D03*
X210100Y135800D03*
X213850Y179850D03*
X205920Y221550D03*
X211900Y253000D03*
X207500D03*
X212400Y281200D03*
X217000Y281000D03*
X212500Y277000D03*
X208000D03*
X223868Y37686D03*
X231780Y37691D03*
X229036Y83000D03*
X231562Y143827D03*
X231611Y138336D03*
X226452Y147300D03*
X233350Y180700D03*
X232225Y193275D03*
X233500Y258958D03*
X228000Y259000D03*
X239599Y37673D03*
X247500Y37642D03*
X238800Y45300D03*
X240200Y59275D03*
X247500Y60000D03*
X244463Y130655D03*
X242950Y155800D03*
X236477Y179357D03*
X239300Y196800D03*
X236861Y184967D03*
X248300Y213500D03*
X248000Y259000D03*
X238500D03*
X243000D03*
X261900Y44900D03*
X255000Y37642D03*
X263100Y37700D03*
X264700Y59400D03*
X256200Y59200D03*
X264189Y98252D03*
X257000Y213500D03*
X252700D03*
X252500Y259000D03*
X271000Y37800D03*
X278800Y37700D03*
X274000Y55800D03*
X268928Y112625D03*
X268895Y107350D03*
X268300Y141869D03*
X269772Y188274D03*
X274700Y222100D03*
X286900Y37800D03*
X294500Y37900D03*
X292500Y60500D03*
X284000Y55800D03*
X288700Y71100D03*
X292100D03*
X295300Y66200D03*
X285100Y129510D03*
X281500Y142100D03*
X295900Y154200D03*
X287700Y211900D03*
X295300Y238100D03*
X285000Y261700D03*
X310348Y37900D03*
X302600Y37800D03*
X302400Y59500D03*
X306100Y90600D03*
X311000Y141731D03*
X297250Y163700D03*
X311242Y158732D03*
X305290Y187836D03*
X301320Y191060D03*
X310500Y195600D03*
X308200D03*
X326096Y37900D03*
X318048Y37700D03*
X311598Y57522D03*
X322548Y58300D03*
X323882Y71643D03*
X318882D03*
X321300Y88200D03*
X325350Y114500D03*
X326313Y122380D03*
X311460Y172078D03*
X323800Y192150D03*
X323789Y188117D03*
X326500Y187900D03*
X311900Y188070D03*
X319500Y212100D03*
X315585Y207787D03*
X324100Y208000D03*
X325200Y221700D03*
X319400Y216200D03*
X313600Y237700D03*
X321400D03*
X322000Y264300D03*
X333700Y38000D03*
X328300Y58200D03*
X337000Y74202D03*
X328882Y71643D03*
X330470Y112515D03*
X330910Y115010D03*
X338421Y153802D03*
X326831Y196119D03*
X337670Y213520D03*
X332974Y210874D03*
X339800Y207400D03*
X330200Y216800D03*
X336000Y219750D03*
X333036Y231910D03*
X327100Y237100D03*
X353100Y56151D03*
X346600Y121100D03*
X355460Y149510D03*
X355413Y156050D03*
X351700Y167300D03*
X350000Y177700D03*
X353321Y180128D03*
X350409Y199755D03*
X354700Y199900D03*
X363583Y37642D03*
X368721Y108528D03*
X365721Y115528D03*
X366400Y112200D03*
X371176Y136890D03*
X364700Y152713D03*
X369500Y237200D03*
Y240600D03*
Y234600D03*
Y244000D03*
X365800Y264900D03*
X362400D03*
X369300D03*
X375400Y37700D03*
X374200Y143294D03*
X380000Y263461D03*
X383500D03*
X376500D03*
X393198Y158940D03*
X399298Y162090D03*
X402505Y159133D03*
X396148Y158940D03*
X399298D03*
X393000Y236200D03*
X397400Y239700D03*
X389500Y275300D03*
X405990Y144251D03*
X409096Y143963D03*
X412900Y157800D03*
X411600Y159600D03*
X408900Y162463D03*
X410408Y170261D03*
X407552Y170424D03*
X415700Y219200D03*
X405700Y246500D03*
X430500Y17000D03*
X426900Y160040D03*
X419340Y170500D03*
X434482Y177021D03*
X419600Y219200D03*
X423900Y257500D03*
X444783Y28451D03*
X434700Y128200D03*
X439276Y159645D03*
X443800Y246100D03*
X445300Y274400D03*
X451000Y257413D03*
X456300Y275300D03*
X474000Y9000D03*
X467200Y4400D03*
X480400Y154050D03*
X467100Y154200D03*
X477000Y154050D03*
X470100Y154200D03*
X473500Y154050D03*
X467700Y245500D03*
X481500Y8900D03*
X489600Y8800D03*
X483800Y154050D03*
X487200Y154100D03*
X497100Y8800D03*
X506800Y12907D03*
X508700Y17207D03*
X506500Y32807D03*
X502000Y89000D03*
X511200Y183400D03*
X500900D03*
X505200Y215000D03*
X514360Y12417D03*
X526000Y12507D03*
X519426Y12318D03*
X522311Y16720D03*
X514300Y20507D03*
X519623Y20457D03*
X522700Y30007D03*
X513005Y32412D03*
X519400Y33340D03*
X526700Y33207D03*
X525740Y88960D03*
X524700Y119500D03*
X515000Y119270D03*
X524700Y145041D03*
X526600Y183500D03*
X513100Y234500D03*
X516500D03*
X537964Y12317D03*
X532500Y13407D03*
X541114Y12307D03*
X528219Y15096D03*
X532472Y20515D03*
X537410Y20584D03*
X529000Y30007D03*
X541950Y33340D03*
X532542Y33307D03*
X537200Y33207D03*
X531500Y219500D03*
X541500Y234900D03*
X547500Y12507D03*
X553720Y12297D03*
X550234Y14997D03*
X553797Y20496D03*
X549500Y29107D03*
X553250Y33207D03*
X547306Y33134D03*
X551800Y69600D03*
X548400Y69700D03*
X555199D03*
X556500Y89000D03*
X546349Y89512D03*
X552100Y136000D03*
X557100D03*
X544954Y183600D03*
X551700Y209800D03*
X550400Y222285D03*
X558448Y12407D03*
X566040Y12317D03*
X566000Y16507D03*
X572200Y28707D03*
X558500Y20507D03*
X573200Y19907D03*
X565470Y33287D03*
X573242Y32462D03*
X560635Y33264D03*
X561999Y69700D03*
X558599D03*
X570715Y89100D03*
X572100Y136000D03*
X567100D03*
X562000Y127800D03*
X562100Y136000D03*
X562000Y144900D03*
X558915Y183603D03*
X569200Y223600D03*
X573470Y12347D03*
X578620Y12357D03*
X585280Y12267D03*
X583700Y28207D03*
X578600Y20307D03*
X579100Y33207D03*
X585550Y33340D03*
X582254Y183313D03*
X590000Y14007D03*
X594500Y4007D03*
X600896Y12407D03*
X601000Y20507D03*
X590500Y30507D03*
X594200Y33607D03*
X600360Y33287D03*
X596845Y89624D03*
X599300Y119270D03*
X588800Y145000D03*
X599200D03*
X590975Y183275D03*
X588800Y205900D03*
X603964Y210400D03*
X600900Y230200D03*
X605700Y12407D03*
X610800Y14807D03*
X605728Y20518D03*
X610500Y30507D03*
X607544Y33340D03*
X617700Y125500D03*
X615700Y230200D03*
X630000Y55300D03*
X627500Y104900D03*
X620000Y112575D03*
X623400Y230100D03*
X640500Y55000D03*
X639500Y136490D03*
X648500Y162600D03*
X655133Y55833D03*
X653000Y93000D03*
X650726Y125724D03*
X664212Y147993D03*
X661600Y156700D03*
X654100Y221800D03*
X675990Y12357D03*
X676600Y20307D03*
X671500Y15007D03*
X671900Y30707D03*
X675970Y33267D03*
X678400Y114500D03*
X668411Y148089D03*
X678500Y141500D03*
X667061Y175239D03*
X676200Y181600D03*
X687602Y12439D03*
X694200Y13507D03*
X681280Y12457D03*
X684500Y15507D03*
X689595Y27883D03*
X685400Y28307D03*
X681700Y20507D03*
X694205Y20302D03*
X693700Y33107D03*
X681280Y33340D03*
X687900Y33327D03*
X693500Y148000D03*
X690000Y159000D03*
X694500D03*
X684700Y179800D03*
X694600Y229800D03*
X699503Y12482D03*
X706360Y12397D03*
X705604Y16949D03*
X710813Y28796D03*
X699104Y20495D03*
X707157Y33333D03*
X700940Y33340D03*
X700089Y91411D03*
X701600Y104900D03*
X701400Y98400D03*
X698000Y181500D03*
X704700Y183800D03*
X710200Y201700D03*
X714000Y12407D03*
X719110Y12347D03*
X725530Y12507D03*
X714100Y20607D03*
X719220Y20553D03*
X721074Y30514D03*
X718350Y33107D03*
X712450Y33340D03*
X725653Y32654D03*
X725632Y49600D03*
X721950Y51950D03*
X722000Y74500D03*
X717000D03*
X715000Y80300D03*
X714500Y85500D03*
X715700Y124200D03*
X727187Y140000D03*
X717000Y187500D03*
X715500Y205837D03*
X737300Y12307D03*
X732110Y12267D03*
X728500Y15507D03*
X742100Y28107D03*
X732000Y20307D03*
X736748D03*
X728500Y27907D03*
X733474Y33340D03*
X738487Y33094D03*
X739500Y75500D03*
X738000Y65700D03*
X738500Y90000D03*
X731340Y82515D03*
X739500Y114900D03*
X741104Y133763D03*
X736900Y162300D03*
X729500D03*
X733400D03*
X737000Y188315D03*
X734000Y205000D03*
X745100Y12256D03*
X744800Y33007D03*
X752500Y49007D03*
X756000Y106000D03*
X758176Y135024D03*
X745104Y129763D03*
X749104Y133763D03*
X745104D03*
X752191Y146613D03*
X745104Y137763D03*
X747000Y162000D03*
X750500D03*
X746000Y182300D03*
X764500Y84800D03*
X760400Y88700D03*
X768100Y89000D03*
X761300Y95700D03*
X768500Y114000D03*
X763600Y168000D03*
X764000Y188000D03*
Y197500D03*
Y192810D03*
Y202310D03*
X769500Y234500D03*
X769400Y252700D03*
X785500Y8000D03*
X784000Y31000D03*
X781500Y51000D03*
X777000Y93100D03*
X774300Y102500D03*
X778500D03*
Y107000D03*
X774300D03*
X783000Y113000D03*
Y118500D03*
Y123000D03*
X779000Y142000D03*
X788515Y144060D03*
X784515D03*
X796515D03*
X792515D03*
X800515D03*
Y148060D03*
X796515D03*
X792515D03*
X810500Y196500D03*
Y192300D03*
X809200Y209500D03*
Y213700D03*
Y218400D03*
X809100Y228600D03*
Y224400D03*
X808700Y238300D03*
Y234100D03*
Y242900D03*
X809500Y251500D03*
Y257000D03*
X808700Y247100D03*
X809700Y285900D03*
X820500Y6500D03*
X821900Y273100D03*
X821600Y285500D03*
G54D31*
X804032Y27032D03*
Y67032D03*
G54D29*
X350197Y231103D03*
G54D11*
X11500Y68500D03*
X12000Y279000D03*
X816000Y280000D03*
G54D16*
X45669Y77185D03*
Y172460D03*
G54D21*
X200197Y282677D03*
X298622D03*
G54D10*
X-19686Y15748D03*
Y573228D03*
X846455Y15748D03*
Y573228D03*
G54D25*
X315613Y100850D03*
X339280Y127380D03*
X434700Y131800D03*
G54D26*
X325300Y112300D03*
X319252Y140949D03*
X324200Y157800D03*
X311417Y153821D03*
X341300Y169600D03*
X332100Y185600D03*
X338000Y185700D03*
X335000Y185500D03*
X332800Y187700D03*
X358500Y137000D03*
X385750Y128517D03*
X380400Y133928D03*
X387000Y143280D03*
X380398Y143418D03*
X383395Y143306D03*
X399452Y133964D03*
X389380Y130100D03*
X393000Y152663D03*
X402900Y149663D03*
X389721Y143320D03*
X393000Y140268D03*
X403132Y144374D03*
X403080Y146931D03*
X399198Y146468D03*
X396192Y146444D03*
X392998Y149718D03*
X399198Y149618D03*
X396182Y149674D03*
X396200Y152763D03*
X396300Y162100D03*
X399300Y152863D03*
Y155963D03*
X403078Y152922D03*
X405500Y131063D03*
X406000Y150200D03*
X407500Y152100D03*
X410400Y152000D03*
X407500Y157600D03*
X407400Y154863D03*
X406100Y159500D03*
X417900Y178363D03*
X431620Y154620D03*
X421697Y174049D03*
X456200Y118900D03*
Y129600D03*
X459700Y133600D03*
X459800Y126200D03*
X456500Y123000D03*
X457700Y167400D03*
X456500Y174900D03*
X454500Y171100D03*
X456900Y193300D03*
X453900Y197000D03*
X456000Y200700D03*
X470400Y178200D03*
X467800Y181800D03*
X469600Y185500D03*
X466000Y189000D03*
G54D27*
X322010Y118573D03*
X323007Y127672D03*
X338048Y196250D03*
X342029Y196427D03*
X349600Y126700D03*
X342760Y187810D03*
X371900Y89000D03*
X368600Y94100D03*
X365000Y94700D03*
X357721Y95100D03*
X360900Y94200D03*
X359942Y110924D03*
X375800Y87000D03*
X383450Y86900D03*
X387200D03*
X379500D03*
X379526Y106396D03*
X381950Y100950D03*
X381550Y117400D03*
X377800Y112063D03*
X386561Y108812D03*
X377713Y121061D03*
X397300Y93100D03*
X390650Y93000D03*
X394100Y94900D03*
X400400Y95000D03*
X393028Y162059D03*
X402373Y155952D03*
X396000Y179000D03*
X414300Y85600D03*
X403800Y87000D03*
X407400Y87400D03*
X411000Y88900D03*
X417785Y162622D03*
X415100Y158100D03*
X408600Y159600D03*
X406000Y162663D03*
X404558Y154835D03*
X408158Y178666D03*
X411342Y185024D03*
X419499Y139064D03*
X423910Y175700D03*
X432712Y172469D03*
X435453Y167560D03*
X435105Y181207D03*
X435453Y185397D03*
X507817Y252248D03*
X511200Y258900D03*
X509244Y272796D03*
X516600Y252200D03*
X521800Y252875D03*
X513776Y258563D03*
X516727Y273122D03*
X521790Y273140D03*
X517100Y265100D03*
X521987D03*
X532900Y255300D03*
X535098Y252600D03*
X540900Y252300D03*
X527400Y252100D03*
X529300Y271000D03*
X528330Y273140D03*
X539937Y272989D03*
X539505Y265100D03*
X534905Y273097D03*
X534700Y265100D03*
X552800Y255300D03*
X545500Y252600D03*
X553485Y252332D03*
X546200Y271000D03*
X554500Y264900D03*
X546900Y273100D03*
X554434Y272914D03*
X560555Y252503D03*
X563376Y256627D03*
X566151Y252115D03*
X572150Y252200D03*
X570200Y269700D03*
X559600Y272900D03*
X572155Y264900D03*
X565700Y273050D03*
X559700Y264900D03*
X572700Y273100D03*
X582300Y254900D03*
X578800Y252200D03*
X577450Y264900D03*
X580107Y270501D03*
X577636Y272947D03*
X643020Y254710D03*
X647800Y252300D03*
X644090Y270420D03*
X648200Y265300D03*
X648291Y273140D03*
X665300Y254700D03*
X661200Y248500D03*
X653600Y252130D03*
X664500Y270000D03*
X653000Y264900D03*
X661600Y272300D03*
X653041Y272989D03*
X669930Y252150D03*
X674636Y252406D03*
X680600Y265000D03*
X675400D03*
X668000Y272890D03*
X680400Y273100D03*
X675400D03*
X690000Y256800D03*
X685390Y254900D03*
X688720Y252090D03*
X693860Y252210D03*
X681900Y252500D03*
X691900Y269300D03*
X683100Y268000D03*
X695500Y265000D03*
Y273100D03*
X687682Y272889D03*
X704137Y254796D03*
X699800Y252230D03*
X701704Y257549D03*
X707490Y252310D03*
X706000Y270500D03*
X700200Y264900D03*
X700300Y273100D03*
X706900Y273000D03*
X712350Y252640D03*
X725950Y252573D03*
X721395Y252175D03*
X721600Y257500D03*
X716737Y252189D03*
X716795Y265000D03*
X721400D03*
X721395Y273100D03*
X713100Y273000D03*
X716737Y272989D03*
X730300Y257900D03*
X734937Y253100D03*
X739750Y252800D03*
X729860Y269810D03*
X734200Y265100D03*
X739111Y264962D03*
X739838Y272813D03*
X727800Y272800D03*
X734510Y273110D03*
X744100Y254800D03*
X749000Y252200D03*
X746737Y272889D03*
G54D28*
X320321Y130528D03*
X351342Y114158D03*
X351000Y111700D03*
X351950Y214800D03*
X346500Y208350D03*
X345500Y213000D03*
X353792Y208466D03*
X355860Y216690D03*
X345300Y216700D03*
X412500Y197300D03*
X405000Y190700D03*
X405800Y196700D03*
X416353Y207249D03*
X421253Y199822D03*
X425642Y209524D03*
X445000Y194500D03*
X443100Y195900D03*
X443000Y192700D03*
X436957Y209867D03*
G54D30*
X384810Y208530D03*
X384644Y205994D03*
X392382Y102149D03*
X400400Y209400D03*
X398500Y208000D03*
X412650Y100197D03*
X434021Y100128D03*
X429933Y197283D03*
%LPC*%
G75*
G54D32*
G01X10636Y-27865D02*
G02I-12000J0D01*
G01X14636D02*
X-17364D01*
G01X5486D02*
G02I-6850J0D01*
G01X-1364Y-43865D02*
Y-11865D01*
G01X14636Y-43865D02*
Y-123865D01*
G01D02*
X1309236D01*
G01X14636Y-79365D02*
X1309236D01*
G01X14636Y-43865D02*
X1309236D01*
G01X521736D02*
Y-123865D01*
G01X659236Y-43865D02*
Y-123865D01*
G01X774236Y-43865D02*
Y-123865D01*
G01X941736Y-43865D02*
Y-123865D01*
G01X1111736Y-43865D02*
Y-123865D01*
G01X1309236Y-43865D02*
Y-123865D01*
G01X1341236Y-27865D02*
X1309236D01*
G01X1337236D02*
G02I-12000J0D01*
G01X1332086D02*
G02I-6850J0D01*
G01X1325236Y-43865D02*
Y-11865D01*
G54D33*
G01X70851Y-113865D02*
Y-96365D01*
G01X80021D02*
Y-113865D01*
G01Y-105115D02*
X70851D01*
G01X92936Y-113865D02*
X91626Y-113573D01*
X90316Y-112407D01*
X89442Y-110365D01*
X89006Y-108032D01*
X89442Y-105698D01*
X90316Y-103657D01*
X91626Y-102490D01*
X92936Y-102199D01*
X94246Y-102490D01*
X95556Y-103657D01*
X96429Y-105698D01*
X96648Y-108032D01*
X96429Y-110365D01*
X95556Y-112407D01*
X94246Y-113573D01*
X92936Y-113865D01*
G01X106724D02*
Y-102199D01*
G01Y-105115D02*
X107598Y-103657D01*
X108908Y-102490D01*
X110654Y-102199D01*
X112182Y-102490D01*
X113493Y-103657D01*
X114148Y-105698D01*
Y-113865D01*
G01X124661Y-105990D02*
X131648D01*
X130993Y-103948D01*
X129901Y-102782D01*
X128373Y-102199D01*
X126844Y-102490D01*
X125534Y-103365D01*
X124661Y-105407D01*
X124224Y-107157D01*
Y-108907D01*
X124661Y-110657D01*
X125753Y-112407D01*
X127063Y-113573D01*
X128591Y-113865D01*
X130119Y-113282D01*
X131648Y-111532D01*
G01X140851Y-119115D02*
X142161Y-119698D01*
X143908Y-119115D01*
X144999Y-117949D01*
X145873Y-116490D01*
X147182Y-111824D01*
X150021Y-102199D01*
G01X143034D02*
X147182Y-111824D01*
G01X182182Y-104532D02*
X183056Y-103657D01*
X183711Y-102199D01*
X184148Y-100156D01*
X183711Y-98407D01*
X182838Y-97240D01*
X181309Y-96365D01*
X175414D01*
Y-113865D01*
X182619D01*
X184148Y-112699D01*
X185021Y-110948D01*
X185458Y-108907D01*
X185021Y-106865D01*
X183711Y-105115D01*
X182182Y-104532D01*
X175414D01*
G01X201866Y-113865D02*
Y-102199D01*
G01Y-104240D02*
X200993Y-103074D01*
X199682Y-102490D01*
X198154Y-102199D01*
X196626Y-102782D01*
X195316Y-103948D01*
X194442Y-105698D01*
X194006Y-108032D01*
X194442Y-110365D01*
X195316Y-112115D01*
X196626Y-113282D01*
X198154Y-113865D01*
X199682Y-113573D01*
X200993Y-112699D01*
X201866Y-111532D01*
G01X219366Y-96365D02*
Y-113865D01*
G01Y-111241D02*
X218493Y-112699D01*
X217182Y-113573D01*
X215654Y-113865D01*
X213908Y-113282D01*
X212598Y-111824D01*
X211724Y-110074D01*
X211506Y-108032D01*
X211724Y-105990D01*
X212598Y-104240D01*
X213908Y-102782D01*
X215654Y-102199D01*
X217182Y-102490D01*
X218274Y-103074D01*
X219366Y-104240D01*
G01X229879Y-118240D02*
X231408Y-119407D01*
X233154Y-119698D01*
X234682Y-119407D01*
X235993Y-117949D01*
X236866Y-115907D01*
Y-102199D01*
G01Y-104532D02*
X235993Y-103365D01*
X234682Y-102490D01*
X233154Y-102199D01*
X231408Y-102782D01*
X230316Y-103948D01*
X229442Y-105990D01*
X229006Y-108032D01*
X229224Y-109782D01*
X230098Y-111824D01*
X231408Y-113282D01*
X233154Y-113865D01*
X234464Y-113573D01*
X235993Y-112407D01*
X236866Y-111241D01*
G01X247161Y-105990D02*
X254148D01*
X253493Y-103948D01*
X252401Y-102782D01*
X250873Y-102199D01*
X249344Y-102490D01*
X248034Y-103365D01*
X247161Y-105407D01*
X246724Y-107157D01*
Y-108907D01*
X247161Y-110657D01*
X248253Y-112407D01*
X249563Y-113573D01*
X251091Y-113865D01*
X252619Y-113282D01*
X254148Y-111532D01*
G01X264879Y-113865D02*
Y-102199D01*
G01Y-104532D02*
X265971Y-103365D01*
X267063Y-102490D01*
X268591Y-102199D01*
X269682Y-102490D01*
X270993Y-103365D01*
G01X298569Y-113865D02*
Y-96365D01*
X303809D01*
X305556Y-97240D01*
X306866Y-99282D01*
X307303Y-101615D01*
X306866Y-103948D01*
X305774Y-105698D01*
X303809Y-106574D01*
X298569D01*
G01X324366Y-113865D02*
Y-102199D01*
G01Y-104240D02*
X323493Y-103074D01*
X322182Y-102490D01*
X320654Y-102199D01*
X319126Y-102782D01*
X317816Y-103948D01*
X316942Y-105698D01*
X316506Y-108032D01*
X316942Y-110365D01*
X317816Y-112115D01*
X319126Y-113282D01*
X320654Y-113865D01*
X322182Y-113573D01*
X323493Y-112699D01*
X324366Y-111532D01*
G01X334224Y-113865D02*
Y-102199D01*
G01Y-105115D02*
X335098Y-103657D01*
X336408Y-102490D01*
X338154Y-102199D01*
X339682Y-102490D01*
X340993Y-103657D01*
X341648Y-105698D01*
Y-113865D01*
G01X355436Y-96365D02*
Y-113865D01*
G01X352379Y-102199D02*
X358493D01*
G01X369224Y-113865D02*
Y-96365D01*
G01Y-104823D02*
X370316Y-103365D01*
X371408Y-102490D01*
X373154Y-102199D01*
X374464Y-102490D01*
X375993Y-103657D01*
X376648Y-105407D01*
Y-113865D01*
G01X387161Y-105990D02*
X394148D01*
X393493Y-103948D01*
X392401Y-102782D01*
X390873Y-102199D01*
X389344Y-102490D01*
X388034Y-103365D01*
X387161Y-105407D01*
X386724Y-107157D01*
Y-108907D01*
X387161Y-110657D01*
X388253Y-112407D01*
X389563Y-113573D01*
X391091Y-113865D01*
X392619Y-113282D01*
X394148Y-111532D01*
G01X404879Y-113865D02*
Y-102199D01*
G01Y-104532D02*
X405971Y-103365D01*
X407063Y-102490D01*
X408591Y-102199D01*
X409682Y-102490D01*
X410993Y-103365D01*
G01X437259Y-113865D02*
Y-96365D01*
X442936Y-110948D01*
X448613Y-96365D01*
Y-113865D01*
G01X462182Y-104532D02*
X463056Y-103657D01*
X463711Y-102199D01*
X464148Y-100156D01*
X463711Y-98407D01*
X462838Y-97240D01*
X461309Y-96365D01*
X455414D01*
Y-113865D01*
X462619D01*
X464148Y-112699D01*
X465021Y-110948D01*
X465458Y-108907D01*
X465021Y-106865D01*
X463711Y-105115D01*
X462182Y-104532D01*
X455414D01*
G01X227259Y-68865D02*
Y-51365D01*
X232936Y-65948D01*
X238613Y-51365D01*
Y-68865D01*
G01X250436D02*
X249126Y-68573D01*
X247816Y-67407D01*
X246942Y-65365D01*
X246506Y-63032D01*
X246942Y-60698D01*
X247816Y-58657D01*
X249126Y-57490D01*
X250436Y-57199D01*
X251746Y-57490D01*
X253056Y-58657D01*
X253929Y-60698D01*
X254148Y-63032D01*
X253929Y-65365D01*
X253056Y-67407D01*
X251746Y-68573D01*
X250436Y-68865D01*
G01X271866Y-51365D02*
Y-68865D01*
G01Y-66241D02*
X270993Y-67699D01*
X269682Y-68573D01*
X268154Y-68865D01*
X266408Y-68282D01*
X265098Y-66824D01*
X264224Y-65074D01*
X264006Y-63032D01*
X264224Y-60990D01*
X265098Y-59240D01*
X266408Y-57782D01*
X268154Y-57199D01*
X269682Y-57490D01*
X270774Y-58074D01*
X271866Y-59240D01*
G01X282161Y-60990D02*
X289148D01*
X288493Y-58948D01*
X287401Y-57782D01*
X285873Y-57199D01*
X284344Y-57490D01*
X283034Y-58365D01*
X282161Y-60407D01*
X281724Y-62157D01*
Y-63907D01*
X282161Y-65657D01*
X283253Y-67407D01*
X284563Y-68573D01*
X286091Y-68865D01*
X287619Y-68282D01*
X289148Y-66532D01*
G01X302936Y-68865D02*
Y-51365D01*
G01X542319Y-68865D02*
Y-51365D01*
X547559D01*
X549306Y-52240D01*
X550616Y-54282D01*
X551053Y-56615D01*
X550616Y-58948D01*
X549524Y-60698D01*
X547559Y-61574D01*
X542319D01*
G01X568989Y-52824D02*
X567679Y-51948D01*
X566151Y-51365D01*
X564404D01*
X562439Y-52240D01*
X560911Y-53698D01*
X559819Y-55449D01*
X558946Y-58365D01*
X558727Y-60990D01*
X559164Y-63615D01*
X559819Y-65365D01*
X561129Y-67115D01*
X562658Y-68282D01*
X564186Y-68865D01*
X565714D01*
X567243Y-68282D01*
X568553Y-67407D01*
X569645Y-66241D01*
G01X583432Y-59532D02*
X584306Y-58657D01*
X584961Y-57199D01*
X585398Y-55156D01*
X584961Y-53407D01*
X584088Y-52240D01*
X582559Y-51365D01*
X576664D01*
Y-68865D01*
X583869D01*
X585398Y-67699D01*
X586271Y-65948D01*
X586708Y-63907D01*
X586271Y-61865D01*
X584961Y-60115D01*
X583432Y-59532D01*
X576664D01*
G01X592636Y-74698D02*
X605736D01*
G01X611664Y-68865D02*
Y-51365D01*
X621708Y-68865D01*
Y-51365D01*
G01X634186Y-68865D02*
X632439Y-68573D01*
X630911Y-67407D01*
X629601Y-65657D01*
X628727Y-63615D01*
X628291Y-61282D01*
Y-58948D01*
X628727Y-56615D01*
X629601Y-54573D01*
X630911Y-52824D01*
X632439Y-51657D01*
X634186Y-51365D01*
X635932Y-51657D01*
X637461Y-52824D01*
X638771Y-54573D01*
X639645Y-56615D01*
X640081Y-58948D01*
Y-61282D01*
X639645Y-63615D01*
X638771Y-65657D01*
X637461Y-67407D01*
X635932Y-68573D01*
X634186Y-68865D01*
G01X555436Y-113865D02*
Y-96365D01*
X552816Y-99865D01*
G01Y-113865D02*
X558056D01*
G01X568133Y-110365D02*
X569442Y-112407D01*
X571189Y-113573D01*
X573154Y-113865D01*
X574901Y-113573D01*
X576648Y-112115D01*
X577739Y-110365D01*
X577958Y-108615D01*
X577521Y-106574D01*
X575993Y-105115D01*
X574464Y-104532D01*
X572499D01*
G01X574464D02*
X575774Y-103657D01*
X576866Y-102199D01*
X577303Y-100449D01*
X576866Y-98698D01*
X575774Y-97240D01*
X573809Y-96365D01*
X571844Y-96657D01*
X569879Y-97824D01*
G01X590436Y-113865D02*
Y-96365D01*
X587816Y-99865D01*
G01Y-113865D02*
X593056D01*
G01X603133Y-110365D02*
X604442Y-112407D01*
X606189Y-113573D01*
X608154Y-113865D01*
X609901Y-113573D01*
X611648Y-112115D01*
X612739Y-110365D01*
X612958Y-108615D01*
X612521Y-106574D01*
X610993Y-105115D01*
X609464Y-104532D01*
X607499D01*
G01X609464D02*
X610774Y-103657D01*
X611866Y-102199D01*
X612303Y-100449D01*
X611866Y-98698D01*
X610774Y-97240D01*
X608809Y-96365D01*
X606844Y-96657D01*
X604879Y-97824D01*
G01X625436Y-96365D02*
X623689Y-96948D01*
X622379Y-98407D01*
X621506Y-100156D01*
X620851Y-102490D01*
X620633Y-105115D01*
X620851Y-107740D01*
X621506Y-110074D01*
X622379Y-111824D01*
X623689Y-113282D01*
X625436Y-113865D01*
X627182Y-113282D01*
X628493Y-111824D01*
X629366Y-110074D01*
X630021Y-107740D01*
X630239Y-105115D01*
X630021Y-102490D01*
X629366Y-100156D01*
X628493Y-98407D01*
X627182Y-96948D01*
X625436Y-96365D01*
G01X685027Y-51365D02*
X690486Y-68865D01*
X695945Y-51365D01*
G01X712353Y-68865D02*
X703619D01*
Y-51365D01*
X712353D01*
G01X708859Y-59823D02*
X703619D01*
G01X721119Y-68865D02*
Y-51365D01*
X726578D01*
X728324Y-52240D01*
X729416Y-53407D01*
X729853Y-55740D01*
X729416Y-58074D01*
X728106Y-59532D01*
X726578Y-60407D01*
X721119D01*
G01X726578D02*
X729853Y-68865D01*
G01X742986Y-69448D02*
X742549Y-69157D01*
Y-68573D01*
X742986Y-68282D01*
X743423Y-68573D01*
Y-69157D01*
X742986Y-69448D01*
G01X707986Y-113865D02*
Y-96365D01*
X705366Y-99865D01*
G01Y-113865D02*
X710606D01*
G01X727232Y-104532D02*
X728106Y-103657D01*
X728761Y-102199D01*
X729198Y-100156D01*
X728761Y-98407D01*
X727888Y-97240D01*
X726359Y-96365D01*
X720464D01*
Y-113865D01*
X727669D01*
X729198Y-112699D01*
X730071Y-110948D01*
X730508Y-108907D01*
X730071Y-106865D01*
X728761Y-105115D01*
X727232Y-104532D01*
X720464D01*
G01X818569Y-96365D02*
Y-113865D01*
X827303D01*
G01X843056D02*
Y-96365D01*
X834977Y-108907D01*
X845895D01*
G01X859246Y-105115D02*
X863613D01*
Y-110365D01*
X862303Y-112115D01*
X860774Y-113282D01*
X858591Y-113865D01*
X856408Y-113282D01*
X854879Y-112115D01*
X853569Y-110365D01*
X852696Y-108323D01*
X852259Y-105990D01*
Y-103948D01*
X852696Y-102199D01*
X853569Y-100156D01*
X854879Y-98407D01*
X856189Y-97240D01*
X857936Y-96365D01*
X859464D01*
X861211Y-96948D01*
X862521Y-98115D01*
G01X870414Y-113865D02*
Y-96365D01*
X880458Y-113865D01*
Y-96365D01*
G01X888133Y-113865D02*
Y-96365D01*
X892499D01*
X894246Y-97240D01*
X895556Y-98407D01*
X896648Y-100156D01*
X897521Y-102199D01*
X897739Y-105115D01*
X897521Y-108032D01*
X896648Y-110074D01*
X895556Y-111824D01*
X894246Y-112990D01*
X892499Y-113865D01*
X888133D01*
G01X818569Y-51365D02*
Y-68865D01*
X827303D01*
G01X844366D02*
Y-57199D01*
G01Y-59240D02*
X843493Y-58074D01*
X842182Y-57490D01*
X840654Y-57199D01*
X839126Y-57782D01*
X837816Y-58948D01*
X836942Y-60698D01*
X836506Y-63032D01*
X836942Y-65365D01*
X837816Y-67115D01*
X839126Y-68282D01*
X840654Y-68865D01*
X842182Y-68573D01*
X843493Y-67699D01*
X844366Y-66532D01*
G01X853351Y-74115D02*
X854661Y-74698D01*
X856408Y-74115D01*
X857499Y-72949D01*
X858373Y-71490D01*
X859682Y-66824D01*
X862521Y-57199D01*
G01X855534D02*
X859682Y-66824D01*
G01X872161Y-60990D02*
X879148D01*
X878493Y-58948D01*
X877401Y-57782D01*
X875873Y-57199D01*
X874344Y-57490D01*
X873034Y-58365D01*
X872161Y-60407D01*
X871724Y-62157D01*
Y-63907D01*
X872161Y-65657D01*
X873253Y-67407D01*
X874563Y-68573D01*
X876091Y-68865D01*
X877619Y-68282D01*
X879148Y-66532D01*
G01X889879Y-68865D02*
Y-57199D01*
G01Y-59532D02*
X890971Y-58365D01*
X892063Y-57490D01*
X893591Y-57199D01*
X894682Y-57490D01*
X895993Y-58365D01*
G01X943619Y-110365D02*
X944711Y-112115D01*
X946021Y-113282D01*
X947549Y-113865D01*
X949296Y-113282D01*
X950606Y-112115D01*
X951916Y-110365D01*
X952353Y-108032D01*
Y-96365D01*
G01X965486Y-113865D02*
X963739Y-113573D01*
X962211Y-112407D01*
X960901Y-110657D01*
X960027Y-108615D01*
X959591Y-106282D01*
Y-103948D01*
X960027Y-101615D01*
X960901Y-99573D01*
X962211Y-97824D01*
X963739Y-96657D01*
X965486Y-96365D01*
X967232Y-96657D01*
X968761Y-97824D01*
X970071Y-99573D01*
X970945Y-101615D01*
X971381Y-103948D01*
Y-106282D01*
X970945Y-108615D01*
X970071Y-110657D01*
X968761Y-112407D01*
X967232Y-113573D01*
X965486Y-113865D01*
G01X978401Y-111532D02*
X980148Y-112990D01*
X982113Y-113865D01*
X983859D01*
X985606Y-112990D01*
X986916Y-111532D01*
X987571Y-109490D01*
X987134Y-107449D01*
X986043Y-105698D01*
X984078Y-104532D01*
X981458Y-103948D01*
X979929Y-102782D01*
X979274Y-100740D01*
X979711Y-98698D01*
X980803Y-97240D01*
X982331Y-96365D01*
X983859D01*
X985388Y-96948D01*
X986698Y-98407D01*
G01X1004853Y-113865D02*
X996119D01*
Y-96365D01*
X1004853D01*
G01X1001359Y-104823D02*
X996119D01*
G01X1013619Y-113865D02*
Y-96365D01*
X1018859D01*
X1020606Y-97240D01*
X1021916Y-99282D01*
X1022353Y-101615D01*
X1021916Y-103948D01*
X1020824Y-105698D01*
X1018859Y-106574D01*
X1013619D01*
G01X1030901Y-113865D02*
Y-96365D01*
G01X1040071D02*
Y-113865D01*
G01Y-105115D02*
X1030901D01*
G01X1066119Y-96365D02*
Y-113865D01*
X1074853D01*
G01X1082527D02*
X1087986Y-96365D01*
X1093445Y-113865D01*
G01X1091479Y-107740D02*
X1084492D01*
G01X1100683Y-96365D02*
Y-108907D01*
X1101556Y-111532D01*
X1103303Y-113282D01*
X1105486Y-113865D01*
X1107669Y-113282D01*
X1109416Y-111532D01*
X1110289Y-108907D01*
Y-96365D01*
G01X960683Y-68865D02*
Y-51365D01*
X965049D01*
X966796Y-52240D01*
X968106Y-53407D01*
X969198Y-55156D01*
X970071Y-57199D01*
X970289Y-60115D01*
X970071Y-63032D01*
X969198Y-65074D01*
X968106Y-66824D01*
X966796Y-67990D01*
X965049Y-68865D01*
X960683D01*
G01X979711Y-60990D02*
X986698D01*
X986043Y-58948D01*
X984951Y-57782D01*
X983423Y-57199D01*
X981894Y-57490D01*
X980584Y-58365D01*
X979711Y-60407D01*
X979274Y-62157D01*
Y-63907D01*
X979711Y-65657D01*
X980803Y-67407D01*
X982113Y-68573D01*
X983641Y-68865D01*
X985169Y-68282D01*
X986698Y-66532D01*
G01X997211Y-66824D02*
X998303Y-67990D01*
X999831Y-68865D01*
X1001141D01*
X1002451Y-68282D01*
X1003324Y-67407D01*
X1003761Y-66241D01*
X1003543Y-64490D01*
X1002669Y-63615D01*
X998739Y-61865D01*
X997866Y-59823D01*
X998303Y-58365D01*
X999176Y-57490D01*
X1000486Y-57199D01*
X1001796Y-57490D01*
X1003106Y-58365D01*
G01X1017986Y-57199D02*
Y-68865D01*
G01Y-52532D02*
X1017549Y-52240D01*
Y-51657D01*
X1017986Y-51365D01*
X1018423Y-51657D01*
Y-52240D01*
X1017986Y-52532D01*
G01X1032429Y-73240D02*
X1033958Y-74407D01*
X1035704Y-74698D01*
X1037232Y-74407D01*
X1038543Y-72949D01*
X1039416Y-70907D01*
Y-57199D01*
G01Y-59532D02*
X1038543Y-58365D01*
X1037232Y-57490D01*
X1035704Y-57199D01*
X1033958Y-57782D01*
X1032866Y-58948D01*
X1031992Y-60990D01*
X1031556Y-63032D01*
X1031774Y-64782D01*
X1032648Y-66824D01*
X1033958Y-68282D01*
X1035704Y-68865D01*
X1037014Y-68573D01*
X1038543Y-67407D01*
X1039416Y-66241D01*
G01X1049274Y-68865D02*
Y-57199D01*
G01Y-60115D02*
X1050148Y-58657D01*
X1051458Y-57490D01*
X1053204Y-57199D01*
X1054732Y-57490D01*
X1056043Y-58657D01*
X1056698Y-60698D01*
Y-68865D01*
G01X1067211Y-60990D02*
X1074198D01*
X1073543Y-58948D01*
X1072451Y-57782D01*
X1070923Y-57199D01*
X1069394Y-57490D01*
X1068084Y-58365D01*
X1067211Y-60407D01*
X1066774Y-62157D01*
Y-63907D01*
X1067211Y-65657D01*
X1068303Y-67407D01*
X1069613Y-68573D01*
X1071141Y-68865D01*
X1072669Y-68282D01*
X1074198Y-66532D01*
G01X1084929Y-68865D02*
Y-57199D01*
G01Y-59532D02*
X1086021Y-58365D01*
X1087113Y-57490D01*
X1088641Y-57199D01*
X1089732Y-57490D01*
X1091043Y-58365D01*
G01X1131686Y-113865D02*
Y-96365D01*
X1129066Y-99865D01*
G01Y-113865D02*
X1134306D01*
G01X1149186D02*
Y-96365D01*
X1146566Y-99865D01*
G01Y-113865D02*
X1151806D01*
G01X1162756Y-114448D02*
X1170616Y-96365D01*
G01X1184186Y-113865D02*
Y-96365D01*
X1181566Y-99865D01*
G01Y-113865D02*
X1186806D01*
G01X1196883Y-110365D02*
X1198192Y-112407D01*
X1199939Y-113573D01*
X1201904Y-113865D01*
X1203651Y-113573D01*
X1205398Y-112115D01*
X1206489Y-110365D01*
X1206708Y-108615D01*
X1206271Y-106574D01*
X1204743Y-105115D01*
X1203214Y-104532D01*
X1201249D01*
G01X1203214D02*
X1204524Y-103657D01*
X1205616Y-102199D01*
X1206053Y-100449D01*
X1205616Y-98698D01*
X1204524Y-97240D01*
X1202559Y-96365D01*
X1200594Y-96657D01*
X1198629Y-97824D01*
G01X1215256Y-114448D02*
X1223116Y-96365D01*
G01X1232538Y-99282D02*
X1233848Y-97532D01*
X1235376Y-96657D01*
X1237123Y-96365D01*
X1239306Y-96948D01*
X1240834Y-98407D01*
X1241271Y-100156D01*
X1241053Y-101907D01*
X1240179Y-103365D01*
X1235813Y-106282D01*
X1233848Y-108323D01*
X1232538Y-111241D01*
X1232101Y-113865D01*
X1241271D01*
G01X1254186Y-96365D02*
X1252439Y-96948D01*
X1251129Y-98407D01*
X1250256Y-100156D01*
X1249601Y-102490D01*
X1249383Y-105115D01*
X1249601Y-107740D01*
X1250256Y-110074D01*
X1251129Y-111824D01*
X1252439Y-113282D01*
X1254186Y-113865D01*
X1255932Y-113282D01*
X1257243Y-111824D01*
X1258116Y-110074D01*
X1258771Y-107740D01*
X1258989Y-105115D01*
X1258771Y-102490D01*
X1258116Y-100156D01*
X1257243Y-98407D01*
X1255932Y-96948D01*
X1254186Y-96365D01*
G01X1271686Y-113865D02*
Y-96365D01*
X1269066Y-99865D01*
G01Y-113865D02*
X1274306D01*
G01X1291806D02*
Y-96365D01*
X1283727Y-108907D01*
X1294645D01*
G01X1179383Y-68865D02*
Y-51365D01*
X1183749D01*
X1185496Y-52240D01*
X1186806Y-53407D01*
X1187898Y-55156D01*
X1188771Y-57199D01*
X1188989Y-60115D01*
X1188771Y-63032D01*
X1187898Y-65074D01*
X1186806Y-66824D01*
X1185496Y-67990D01*
X1183749Y-68865D01*
X1179383D01*
G01X1205616D02*
Y-57199D01*
G01Y-59240D02*
X1204743Y-58074D01*
X1203432Y-57490D01*
X1201904Y-57199D01*
X1200376Y-57782D01*
X1199066Y-58948D01*
X1198192Y-60698D01*
X1197756Y-63032D01*
X1198192Y-65365D01*
X1199066Y-67115D01*
X1200376Y-68282D01*
X1201904Y-68865D01*
X1203432Y-68573D01*
X1204743Y-67699D01*
X1205616Y-66532D01*
G01X1219186Y-51365D02*
Y-68865D01*
G01X1216129Y-57199D02*
X1222243D01*
G01X1233411Y-60990D02*
X1240398D01*
X1239743Y-58948D01*
X1238651Y-57782D01*
X1237123Y-57199D01*
X1235594Y-57490D01*
X1234284Y-58365D01*
X1233411Y-60407D01*
X1232974Y-62157D01*
Y-63907D01*
X1233411Y-65657D01*
X1234503Y-67407D01*
X1235813Y-68573D01*
X1237341Y-68865D01*
X1238869Y-68282D01*
X1240398Y-66532D01*
M02*
